(kicad_sch
	(version 20250114)
	(generator "eeschema")
	(generator_version "9.0")
	(paper "A3")
	(title_block
		(title "COM Express 7 Baseboard")
		(date "2025-02-04")
		(rev "1.1.2")
		(company "Antmicro Ltd")
		(comment 1 "www.antmicro.com")
	)
	(rectangle
		(start 270.51 189.23)
		(end 297.18 198.12)
		(stroke
			(width 0)
			(type default)
		)
		(fill
			(type none)
		)
	)
	(text "ADDR: 0x41"
		(exclude_from_sim no)
		(at 173.99 166.37 0)
		(effects
			(font
				(size 1.27 1.27)
			)
			(justify left bottom)
		)
	)
	(text "+3V3_AON LDO"
		(exclude_from_sim no)
		(at 342.9 186.69 0)
		(effects
			(font
				(size 2 2)
				(thickness 0.4)
				(bold yes)
			)
			(justify left bottom)
		)
	)
	(text "Sequence:\n+5V_{AON}\n+3V3_{AON}\n*Power button*\n+12V\n+5V\n+3V3\n+1V8\n+1V0\n"
		(exclude_from_sim no)
		(at 170.18 200.66 0)
		(effects
			(font
				(size 1.27 1.27)
			)
			(justify left bottom)
		)
	)
	(text "+12V source\nand bulk decoupling"
		(exclude_from_sim no)
		(at 53.34 190.5 0)
		(effects
			(font
				(size 2 2)
				(thickness 0.4)
				(bold yes)
			)
			(justify left bottom)
		)
	)
	(text "V_{out} = 1.8 V\nf_{SW} = 1200 kHz\nI_{L} = 1.0 A\nΔI_{L} = 71% \nI_{Lpeak} = 1.35 A"
		(exclude_from_sim no)
		(at 290.83 157.48 0)
		(effects
			(font
				(size 1.27 1.27)
			)
			(justify left bottom)
		)
	)
	(text "I_LED = (VCC-V_LED)/R\nV_LED ≈ 2.1V\nTarget I_LED = 5mA"
		(exclude_from_sim no)
		(at 271.78 196.85 0)
		(effects
			(font
				(size 1.27 1.27)
			)
			(justify left bottom)
		)
	)
	(text "ADDR: 0x40"
		(exclude_from_sim no)
		(at 54.61 254 0)
		(effects
			(font
				(size 1.27 1.27)
			)
			(justify left bottom)
		)
	)
	(text "+1V0 DC/DC converter"
		(exclude_from_sim no)
		(at 99.06 17.78 0)
		(effects
			(font
				(size 2 2)
				(thickness 0.4)
				(bold yes)
			)
			(justify left bottom)
		)
	)
	(text "V_{out} = 1.0 V\nf_{SW} = 500 kHz\nI_{L} = 5.5 A\nΔI_{L} = 19% \nI_{Lpeak} = 6.02 A"
		(exclude_from_sim no)
		(at 132.08 80.01 0)
		(effects
			(font
				(size 1.27 1.27)
			)
			(justify left bottom)
		)
	)
	(text "~120 ms delay"
		(exclude_from_sim no)
		(at 179.07 252.73 0)
		(effects
			(font
				(size 1.27 1.27)
			)
			(justify left bottom)
		)
	)
	(text "+5V DC/DC converter"
		(exclude_from_sim no)
		(at 297.18 20.32 0)
		(effects
			(font
				(size 2 2)
				(thickness 0.4)
				(bold yes)
			)
			(justify left bottom)
		)
	)
	(text "PSU rail description:\n* +12V_{AON} - Input power\n\nAlways on rails:\n* +5V_{AON}\n* +3V3_{AON}\n\nBoard rails (PSON == 1):\n* +12V\n* +5V\n* +3V3\n* +1V8\n* +1V0"
		(exclude_from_sim no)
		(at 137.16 209.55 0)
		(effects
			(font
				(size 1.27 1.27)
			)
			(justify left bottom)
		)
	)
	(text "From backplane\nconnector"
		(exclude_from_sim no)
		(at 13.97 213.36 0)
		(effects
			(font
				(size 1.27 1.27)
			)
			(justify left bottom)
		)
	)
	(text "1V0 is last in\nPG chain so then\nif it's PG is high\nall rails should\nbe OK"
		(exclude_from_sim no)
		(at 138.43 237.49 0)
		(effects
			(font
				(size 1.27 1.27)
			)
			(justify left bottom)
		)
	)
	(text "V_{out} = 3.3 V\nf_{SW} = 500 kHz\nI_{L} = 11.0 A\nΔI_{L} = 25% \nI_{Lpeak} = 12.4 A"
		(exclude_from_sim no)
		(at 132.08 160.02 0)
		(effects
			(font
				(size 1.27 1.27)
			)
			(justify left bottom)
		)
	)
	(text "V_{out} = 5.0 V\nf_{SW} = 1200 kHz\nI_{L} = 4.0 A\nΔI_{L} = 34% \nI_{Lpeak} = 4.68 A"
		(exclude_from_sim no)
		(at 270.51 78.74 0)
		(effects
			(font
				(size 1.27 1.27)
			)
			(justify left bottom)
		)
	)
	(text "+1V8 DC/DC converter"
		(exclude_from_sim no)
		(at 297.18 106.68 0)
		(effects
			(font
				(size 2 2)
				(thickness 0.4)
				(bold yes)
			)
			(justify left bottom)
		)
	)
	(text "Backplane is responsible\nfor backfeed protection"
		(exclude_from_sim no)
		(at 19.05 237.49 0)
		(effects
			(font
				(size 1.27 1.27)
			)
			(justify left bottom)
		)
	)
	(text "+3V3 DC/DC converter"
		(exclude_from_sim no)
		(at 99.06 106.68 0)
		(effects
			(font
				(size 2 2)
				(thickness 0.4)
				(bold yes)
			)
			(justify left bottom)
		)
	)
	(text "Power LEDs and testpoints"
		(exclude_from_sim no)
		(at 232.41 186.69 0)
		(effects
			(font
				(size 2 2)
				(thickness 0.4)
				(bold yes)
			)
			(justify left bottom)
		)
	)
	(text "ADDR: 0x42"
		(exclude_from_sim no)
		(at 325.12 90.17 0)
		(effects
			(font
				(size 1.27 1.27)
			)
			(justify left bottom)
		)
	)
	(junction
		(at 139.7 137.16)
		(diameter 0)
		(color 0 0 0 0)
	)
	(junction
		(at 68.58 223.52)
		(diameter 0)
		(color 0 0 0 0)
	)
	(junction
		(at 236.22 201.93)
		(diameter 0)
		(color 0 0 0 0)
	)
	(junction
		(at 320.04 134.62)
		(diameter 0)
		(color 0 0 0 0)
	)
	(junction
		(at 377.19 66.04)
		(diameter 0)
		(color 0 0 0 0)
	)
	(junction
		(at 248.92 52.07)
		(diameter 0)
		(color 0 0 0 0)
	)
	(junction
		(at 88.9 246.38)
		(diameter 0)
		(color 0 0 0 0)
	)
	(junction
		(at 346.71 55.88)
		(diameter 0)
		(color 0 0 0 0)
	)
	(junction
		(at 227.33 246.38)
		(diameter 0)
		(color 0 0 0 0)
	)
	(junction
		(at 334.01 219.71)
		(diameter 0)
		(color 0 0 0 0)
	)
	(junction
		(at 290.83 63.5)
		(diameter 0)
		(color 0 0 0 0)
	)
	(junction
		(at 248.92 60.96)
		(diameter 0)
		(color 0 0 0 0)
	)
	(junction
		(at 254 207.01)
		(diameter 0)
		(color 0 0 0 0)
	)
	(junction
		(at 69.85 223.52)
		(diameter 0)
		(color 0 0 0 0)
	)
	(junction
		(at 401.32 55.88)
		(diameter 0)
		(color 0 0 0 0)
	)
	(junction
		(at 91.44 134.62)
		(diameter 0)
		(color 0 0 0 0)
	)
	(junction
		(at 340.36 86.36)
		(diameter 0)
		(color 0 0 0 0)
	)
	(junction
		(at 330.2 134.62)
		(diameter 0)
		(color 0 0 0 0)
	)
	(junction
		(at 236.22 248.92)
		(diameter 0)
		(color 0 0 0 0)
	)
	(junction
		(at 170.18 245.11)
		(diameter 0)
		(color 0 0 0 0)
	)
	(junction
		(at 139.7 57.15)
		(diameter 0)
		(color 0 0 0 0)
	)
	(junction
		(at 254 254)
		(diameter 0)
		(color 0 0 0 0)
	)
	(junction
		(at 160.02 129.54)
		(diameter 0)
		(color 0 0 0 0)
	)
	(junction
		(at 152.4 242.57)
		(diameter 0)
		(color 0 0 0 0)
	)
	(junction
		(at 139.7 49.53)
		(diameter 0)
		(color 0 0 0 0)
	)
	(junction
		(at 171.45 129.54)
		(diameter 0)
		(color 0 0 0 0)
	)
	(junction
		(at 124.46 147.32)
		(diameter 0)
		(color 0 0 0 0)
	)
	(junction
		(at 69.85 250.19)
		(diameter 0)
		(color 0 0 0 0)
	)
	(junction
		(at 58.42 124.46)
		(diameter 0)
		(color 0 0 0 0)
	)
	(junction
		(at 67.31 44.45)
		(diameter 0)
		(color 0 0 0 0)
	)
	(junction
		(at 76.2 223.52)
		(diameter 0)
		(color 0 0 0 0)
	)
	(junction
		(at 309.88 142.24)
		(diameter 0)
		(color 0 0 0 0)
	)
	(junction
		(at 48.26 124.46)
		(diameter 0)
		(color 0 0 0 0)
	)
	(junction
		(at 322.58 55.88)
		(diameter 0)
		(color 0 0 0 0)
	)
	(junction
		(at 48.26 223.52)
		(diameter 0)
		(color 0 0 0 0)
	)
	(junction
		(at 237.49 52.07)
		(diameter 0)
		(color 0 0 0 0)
	)
	(junction
		(at 388.62 219.71)
		(diameter 0)
		(color 0 0 0 0)
	)
	(junction
		(at 90.17 54.61)
		(diameter 0)
		(color 0 0 0 0)
	)
	(junction
		(at 130.81 49.53)
		(diameter 0)
		(color 0 0 0 0)
	)
	(junction
		(at 189.23 162.56)
		(diameter 0)
		(color 0 0 0 0)
	)
	(junction
		(at 68.58 137.16)
		(diameter 0)
		(color 0 0 0 0)
	)
	(junction
		(at 266.7 130.81)
		(diameter 0)
		(color 0 0 0 0)
	)
	(junction
		(at 90.17 67.31)
		(diameter 0)
		(color 0 0 0 0)
	)
	(junction
		(at 245.11 224.79)
		(diameter 0)
		(color 0 0 0 0)
	)
	(junction
		(at 179.07 49.53)
		(diameter 0)
		(color 0 0 0 0)
	)
	(junction
		(at 363.22 55.88)
		(diameter 0)
		(color 0 0 0 0)
	)
	(junction
		(at 300.99 55.88)
		(diameter 0)
		(color 0 0 0 0)
	)
	(junction
		(at 104.14 62.23)
		(diameter 0)
		(color 0 0 0 0)
	)
	(junction
		(at 139.7 129.54)
		(diameter 0)
		(color 0 0 0 0)
	)
	(junction
		(at 163.83 227.33)
		(diameter 0)
		(color 0 0 0 0)
	)
	(junction
		(at 69.85 242.57)
		(diameter 0)
		(color 0 0 0 0)
	)
	(junction
		(at 228.6 52.07)
		(diameter 0)
		(color 0 0 0 0)
	)
	(junction
		(at 199.39 129.54)
		(diameter 0)
		(color 0 0 0 0)
	)
	(junction
		(at 104.14 142.24)
		(diameter 0)
		(color 0 0 0 0)
	)
	(junction
		(at 77.47 44.45)
		(diameter 0)
		(color 0 0 0 0)
	)
	(junction
		(at 160.02 49.53)
		(diameter 0)
		(color 0 0 0 0)
	)
	(junction
		(at 259.08 66.04)
		(diameter 0)
		(color 0 0 0 0)
	)
	(junction
		(at 257.81 130.81)
		(diameter 0)
		(color 0 0 0 0)
	)
	(junction
		(at 393.7 55.88)
		(diameter 0)
		(color 0 0 0 0)
	)
	(junction
		(at 227.33 199.39)
		(diameter 0)
		(color 0 0 0 0)
	)
	(junction
		(at 130.81 129.54)
		(diameter 0)
		(color 0 0 0 0)
	)
	(junction
		(at 93.98 223.52)
		(diameter 0)
		(color 0 0 0 0)
	)
	(junction
		(at 344.17 219.71)
		(diameter 0)
		(color 0 0 0 0)
	)
	(junction
		(at 76.2 129.54)
		(diameter 0)
		(color 0 0 0 0)
	)
	(junction
		(at 309.88 134.62)
		(diameter 0)
		(color 0 0 0 0)
	)
	(junction
		(at 358.14 55.88)
		(diameter 0)
		(color 0 0 0 0)
	)
	(junction
		(at 290.83 55.88)
		(diameter 0)
		(color 0 0 0 0)
	)
	(junction
		(at 91.44 147.32)
		(diameter 0)
		(color 0 0 0 0)
	)
	(junction
		(at 116.84 223.52)
		(diameter 0)
		(color 0 0 0 0)
	)
	(junction
		(at 340.36 55.88)
		(diameter 0)
		(color 0 0 0 0)
	)
	(junction
		(at 149.86 49.53)
		(diameter 0)
		(color 0 0 0 0)
	)
	(junction
		(at 99.06 233.68)
		(diameter 0)
		(color 0 0 0 0)
	)
	(junction
		(at 372.11 55.88)
		(diameter 0)
		(color 0 0 0 0)
	)
	(junction
		(at 321.31 78.74)
		(diameter 0)
		(color 0 0 0 0)
	)
	(junction
		(at 124.46 67.31)
		(diameter 0)
		(color 0 0 0 0)
	)
	(junction
		(at 189.23 154.94)
		(diameter 0)
		(color 0 0 0 0)
	)
	(junction
		(at 254 271.78)
		(diameter 0)
		(color 0 0 0 0)
	)
	(junction
		(at 76.2 137.16)
		(diameter 0)
		(color 0 0 0 0)
	)
	(junction
		(at 271.78 237.49)
		(diameter 0)
		(color 0 0 0 0)
	)
	(junction
		(at 368.3 82.55)
		(diameter 0)
		(color 0 0 0 0)
	)
	(junction
		(at 340.36 78.74)
		(diameter 0)
		(color 0 0 0 0)
	)
	(junction
		(at 375.92 219.71)
		(diameter 0)
		(color 0 0 0 0)
	)
	(junction
		(at 52.07 250.19)
		(diameter 0)
		(color 0 0 0 0)
	)
	(junction
		(at 149.86 129.54)
		(diameter 0)
		(color 0 0 0 0)
	)
	(junction
		(at 368.3 78.74)
		(diameter 0)
		(color 0 0 0 0)
	)
	(junction
		(at 104.14 134.62)
		(diameter 0)
		(color 0 0 0 0)
	)
	(junction
		(at 311.15 55.88)
		(diameter 0)
		(color 0 0 0 0)
	)
	(junction
		(at 189.23 129.54)
		(diameter 0)
		(color 0 0 0 0)
	)
	(junction
		(at 254 224.79)
		(diameter 0)
		(color 0 0 0 0)
	)
	(junction
		(at 278.13 144.78)
		(diameter 0)
		(color 0 0 0 0)
	)
	(junction
		(at 245.11 251.46)
		(diameter 0)
		(color 0 0 0 0)
	)
	(junction
		(at 35.56 223.52)
		(diameter 0)
		(color 0 0 0 0)
	)
	(junction
		(at 236.22 271.78)
		(diameter 0)
		(color 0 0 0 0)
	)
	(junction
		(at 245.11 204.47)
		(diameter 0)
		(color 0 0 0 0)
	)
	(junction
		(at 271.78 271.78)
		(diameter 0)
		(color 0 0 0 0)
	)
	(junction
		(at 351.79 134.62)
		(diameter 0)
		(color 0 0 0 0)
	)
	(junction
		(at 236.22 224.79)
		(diameter 0)
		(color 0 0 0 0)
	)
	(junction
		(at 52.07 223.52)
		(diameter 0)
		(color 0 0 0 0)
	)
	(junction
		(at 198.12 240.03)
		(diameter 0)
		(color 0 0 0 0)
	)
	(no_connect
		(at 123.19 139.7)
	)
	(no_connect
		(at 123.19 59.69)
	)
	(bus_entry
		(at 43.18 243.84)
		(size 1.27 1.27)
		(stroke
			(width 0)
			(type default)
		)
	)
	(bus_entry
		(at 43.18 241.3)
		(size 1.27 1.27)
		(stroke
			(width 0)
			(type default)
		)
	)
	(bus_entry
		(at 162.56 153.67)
		(size 1.27 1.27)
		(stroke
			(width 0)
			(type default)
		)
	)
	(bus_entry
		(at 311.15 77.47)
		(size 1.27 1.27)
		(stroke
			(width 0)
			(type default)
		)
	)
	(bus_entry
		(at 311.15 80.01)
		(size 1.27 1.27)
		(stroke
			(width 0)
			(type default)
		)
	)
	(bus_entry
		(at 162.56 156.21)
		(size 1.27 1.27)
		(stroke
			(width 0)
			(type default)
		)
	)
	(wire
		(pts
			(xy 227.33 246.38) (xy 227.33 256.54)
		)
		(stroke
			(width 0)
			(type default)
		)
	)
	(wire
		(pts
			(xy 351.79 148.59) (xy 351.79 144.78)
		)
		(stroke
			(width 0)
			(type default)
		)
	)
	(wire
		(pts
			(xy 260.35 63.5) (xy 259.08 63.5)
		)
		(stroke
			(width 0)
			(type default)
		)
	)
	(wire
		(pts
			(xy 69.85 248.92) (xy 69.85 250.19)
		)
		(stroke
			(width 0)
			(type default)
		)
	)
	(wire
		(pts
			(xy 351.79 133.35) (xy 351.79 134.62)
		)
		(stroke
			(width 0)
			(type default)
		)
	)
	(wire
		(pts
			(xy 198.12 240.03) (xy 198.12 241.3)
		)
		(stroke
			(width 0)
			(type default)
		)
	)
	(wire
		(pts
			(xy 309.88 134.62) (xy 309.88 135.89)
		)
		(stroke
			(width 0)
			(type default)
		)
	)
	(wire
		(pts
			(xy 68.58 137.16) (xy 68.58 139.7)
		)
		(stroke
			(width 0)
			(type default)
		)
	)
	(wire
		(pts
			(xy 124.46 68.58) (xy 124.46 67.31)
		)
		(stroke
			(width 0)
			(type default)
		)
	)
	(wire
		(pts
			(xy 189.23 162.56) (xy 189.23 163.83)
		)
		(stroke
			(width 0)
			(type default)
		)
	)
	(wire
		(pts
			(xy 171.45 227.33) (xy 163.83 227.33)
		)
		(stroke
			(width 0)
			(type default)
		)
	)
	(wire
		(pts
			(xy 146.05 242.57) (xy 152.4 242.57)
		)
		(stroke
			(width 0)
			(type default)
		)
	)
	(wire
		(pts
			(xy 48.26 223.52) (xy 48.26 226.06)
		)
		(stroke
			(width 0)
			(type default)
		)
	)
	(wire
		(pts
			(xy 259.08 63.5) (xy 259.08 66.04)
		)
		(stroke
			(width 0)
			(type default)
		)
	)
	(wire
		(pts
			(xy 359.41 82.55) (xy 360.68 82.55)
		)
		(stroke
			(width 0)
			(type default)
		)
	)
	(wire
		(pts
			(xy 171.45 129.54) (xy 176.53 129.54)
		)
		(stroke
			(width 0)
			(type default)
		)
	)
	(wire
		(pts
			(xy 228.6 52.07) (xy 237.49 52.07)
		)
		(stroke
			(width 0)
			(type default)
		)
	)
	(wire
		(pts
			(xy 266.7 138.43) (xy 266.7 140.97)
		)
		(stroke
			(width 0)
			(type default)
		)
	)
	(wire
		(pts
			(xy 363.22 53.34) (xy 363.22 55.88)
		)
		(stroke
			(width 0)
			(type default)
		)
	)
	(wire
		(pts
			(xy 330.2 134.62) (xy 339.09 134.62)
		)
		(stroke
			(width 0)
			(type default)
		)
	)
	(wire
		(pts
			(xy 304.8 134.62) (xy 309.88 134.62)
		)
		(stroke
			(width 0)
			(type default)
		)
	)
	(wire
		(pts
			(xy 189.23 129.54) (xy 199.39 129.54)
		)
		(stroke
			(width 0)
			(type default)
		)
	)
	(wire
		(pts
			(xy 254 271.78) (xy 271.78 271.78)
		)
		(stroke
			(width 0)
			(type default)
		)
	)
	(wire
		(pts
			(xy 124.46 67.31) (xy 123.19 67.31)
		)
		(stroke
			(width 0)
			(type default)
		)
	)
	(wire
		(pts
			(xy 88.9 246.38) (xy 88.9 247.65)
		)
		(stroke
			(width 0)
			(type default)
		)
	)
	(wire
		(pts
			(xy 368.3 78.74) (xy 369.57 78.74)
		)
		(stroke
			(width 0)
			(type default)
		)
	)
	(wire
		(pts
			(xy 259.08 66.04) (xy 260.35 66.04)
		)
		(stroke
			(width 0)
			(type default)
		)
	)
	(wire
		(pts
			(xy 139.7 129.54) (xy 149.86 129.54)
		)
		(stroke
			(width 0)
			(type default)
		)
	)
	(wire
		(pts
			(xy 259.08 67.31) (xy 259.08 66.04)
		)
		(stroke
			(width 0)
			(type default)
		)
	)
	(wire
		(pts
			(xy 187.96 149.86) (xy 189.23 149.86)
		)
		(stroke
			(width 0)
			(type default)
		)
	)
	(wire
		(pts
			(xy 130.81 129.54) (xy 133.35 129.54)
		)
		(stroke
			(width 0)
			(type default)
		)
	)
	(wire
		(pts
			(xy 254 222.25) (xy 254 224.79)
		)
		(stroke
			(width 0)
			(type default)
		)
	)
	(wire
		(pts
			(xy 245.11 204.47) (xy 245.11 209.55)
		)
		(stroke
			(width 0)
			(type default)
		)
	)
	(wire
		(pts
			(xy 346.71 53.34) (xy 346.71 55.88)
		)
		(stroke
			(width 0)
			(type default)
		)
	)
	(bus
		(pts
			(xy 311.15 77.47) (xy 309.88 76.2)
		)
		(stroke
			(width 0)
			(type default)
		)
	)
	(wire
		(pts
			(xy 67.31 129.54) (xy 68.58 129.54)
		)
		(stroke
			(width 0)
			(type default)
		)
	)
	(wire
		(pts
			(xy 248.92 52.07) (xy 257.81 52.07)
		)
		(stroke
			(width 0)
			(type default)
		)
	)
	(wire
		(pts
			(xy 280.67 237.49) (xy 280.67 238.76)
		)
		(stroke
			(width 0)
			(type default)
		)
	)
	(wire
		(pts
			(xy 124.46 144.78) (xy 124.46 147.32)
		)
		(stroke
			(width 0)
			(type default)
		)
	)
	(wire
		(pts
			(xy 254 271.78) (xy 254 274.32)
		)
		(stroke
			(width 0)
			(type default)
		)
	)
	(wire
		(pts
			(xy 130.81 49.53) (xy 133.35 49.53)
		)
		(stroke
			(width 0)
			(type default)
		)
	)
	(wire
		(pts
			(xy 76.2 129.54) (xy 76.2 137.16)
		)
		(stroke
			(width 0)
			(type default)
		)
	)
	(wire
		(pts
			(xy 383.54 219.71) (xy 388.62 219.71)
		)
		(stroke
			(width 0)
			(type default)
		)
	)
	(wire
		(pts
			(xy 311.15 55.88) (xy 311.15 60.96)
		)
		(stroke
			(width 0)
			(type default)
		)
	)
	(wire
		(pts
			(xy 368.3 82.55) (xy 368.3 83.82)
		)
		(stroke
			(width 0)
			(type default)
		)
	)
	(wire
		(pts
			(xy 274.32 139.7) (xy 279.4 139.7)
		)
		(stroke
			(width 0)
			(type default)
		)
	)
	(wire
		(pts
			(xy 227.33 222.25) (xy 227.33 224.79)
		)
		(stroke
			(width 0)
			(type default)
		)
	)
	(wire
		(pts
			(xy 165.1 166.37) (xy 170.18 166.37)
		)
		(stroke
			(width 0)
			(type default)
		)
	)
	(wire
		(pts
			(xy 172.72 149.86) (xy 171.45 149.86)
		)
		(stroke
			(width 0)
			(type default)
		)
	)
	(wire
		(pts
			(xy 386.08 55.88) (xy 393.7 55.88)
		)
		(stroke
			(width 0)
			(type default)
		)
	)
	(wire
		(pts
			(xy 199.39 143.51) (xy 199.39 139.7)
		)
		(stroke
			(width 0)
			(type default)
		)
	)
	(wire
		(pts
			(xy 254 265.43) (xy 245.11 265.43)
		)
		(stroke
			(width 0)
			(type default)
		)
	)
	(wire
		(pts
			(xy 76.2 149.86) (xy 76.2 154.94)
		)
		(stroke
			(width 0)
			(type default)
		)
	)
	(wire
		(pts
			(xy 123.19 64.77) (xy 124.46 64.77)
		)
		(stroke
			(width 0)
			(type default)
		)
	)
	(wire
		(pts
			(xy 375.92 219.71) (xy 375.92 220.98)
		)
		(stroke
			(width 0)
			(type default)
		)
	)
	(wire
		(pts
			(xy 139.7 135.89) (xy 139.7 137.16)
		)
		(stroke
			(width 0)
			(type default)
		)
	)
	(wire
		(pts
			(xy 116.84 223.52) (xy 116.84 226.06)
		)
		(stroke
			(width 0)
			(type default)
		)
	)
	(wire
		(pts
			(xy 294.64 142.24) (xy 309.88 142.24)
		)
		(stroke
			(width 0)
			(type default)
		)
	)
	(wire
		(pts
			(xy 248.92 59.69) (xy 248.92 60.96)
		)
		(stroke
			(width 0)
			(type default)
		)
	)
	(wire
		(pts
			(xy 187.96 154.94) (xy 189.23 154.94)
		)
		(stroke
			(width 0)
			(type default)
		)
	)
	(wire
		(pts
			(xy 276.86 207.01) (xy 276.86 209.55)
		)
		(stroke
			(width 0)
			(type default)
		)
	)
	(wire
		(pts
			(xy 261.62 257.81) (xy 254 257.81)
		)
		(stroke
			(width 0)
			(type default)
		)
	)
	(wire
		(pts
			(xy 52.07 250.19) (xy 52.07 247.65)
		)
		(stroke
			(width 0)
			(type default)
		)
	)
	(wire
		(pts
			(xy 227.33 269.24) (xy 227.33 271.78)
		)
		(stroke
			(width 0)
			(type default)
		)
	)
	(wire
		(pts
			(xy 97.79 142.24) (xy 104.14 142.24)
		)
		(stroke
			(width 0)
			(type default)
		)
	)
	(wire
		(pts
			(xy 339.09 86.36) (xy 340.36 86.36)
		)
		(stroke
			(width 0)
			(type default)
		)
	)
	(wire
		(pts
			(xy 99.06 252.73) (xy 99.06 250.19)
		)
		(stroke
			(width 0)
			(type default)
		)
	)
	(wire
		(pts
			(xy 194.31 154.94) (xy 194.31 153.67)
		)
		(stroke
			(width 0)
			(type default)
		)
	)
	(wire
		(pts
			(xy 345.44 78.74) (xy 345.44 76.2)
		)
		(stroke
			(width 0)
			(type default)
		)
	)
	(wire
		(pts
			(xy 69.85 242.57) (xy 76.2 242.57)
		)
		(stroke
			(width 0)
			(type default)
		)
	)
	(wire
		(pts
			(xy 254 224.79) (xy 254 227.33)
		)
		(stroke
			(width 0)
			(type default)
		)
	)
	(wire
		(pts
			(xy 275.59 55.88) (xy 280.67 55.88)
		)
		(stroke
			(width 0)
			(type default)
		)
	)
	(wire
		(pts
			(xy 149.86 63.5) (xy 149.86 59.69)
		)
		(stroke
			(width 0)
			(type default)
		)
	)
	(wire
		(pts
			(xy 236.22 222.25) (xy 236.22 224.79)
		)
		(stroke
			(width 0)
			(type default)
		)
	)
	(wire
		(pts
			(xy 66.04 154.94) (xy 66.04 152.4)
		)
		(stroke
			(width 0)
			(type default)
		)
	)
	(wire
		(pts
			(xy 320.04 148.59) (xy 320.04 144.78)
		)
		(stroke
			(width 0)
			(type default)
		)
	)
	(wire
		(pts
			(xy 285.75 55.88) (xy 290.83 55.88)
		)
		(stroke
			(width 0)
			(type default)
		)
	)
	(wire
		(pts
			(xy 191.77 240.03) (xy 198.12 240.03)
		)
		(stroke
			(width 0)
			(type default)
		)
	)
	(wire
		(pts
			(xy 90.17 64.77) (xy 90.17 67.31)
		)
		(stroke
			(width 0)
			(type default)
		)
	)
	(wire
		(pts
			(xy 105.41 134.62) (xy 104.14 134.62)
		)
		(stroke
			(width 0)
			(type default)
		)
	)
	(wire
		(pts
			(xy 311.15 69.85) (xy 311.15 66.04)
		)
		(stroke
			(width 0)
			(type default)
		)
	)
	(wire
		(pts
			(xy 170.18 245.11) (xy 161.29 245.11)
		)
		(stroke
			(width 0)
			(type default)
		)
	)
	(wire
		(pts
			(xy 254 254) (xy 257.81 254)
		)
		(stroke
			(width 0)
			(type default)
		)
	)
	(wire
		(pts
			(xy 53.34 237.49) (xy 52.07 237.49)
		)
		(stroke
			(width 0)
			(type default)
		)
	)
	(wire
		(pts
			(xy 160.02 143.51) (xy 160.02 139.7)
		)
		(stroke
			(width 0)
			(type default)
		)
	)
	(wire
		(pts
			(xy 68.58 242.57) (xy 69.85 242.57)
		)
		(stroke
			(width 0)
			(type default)
		)
	)
	(wire
		(pts
			(xy 227.33 271.78) (xy 236.22 271.78)
		)
		(stroke
			(width 0)
			(type default)
		)
	)
	(bus
		(pts
			(xy 299.72 76.2) (xy 309.88 76.2)
		)
		(stroke
			(width 0)
			(type default)
		)
	)
	(wire
		(pts
			(xy 35.56 223.52) (xy 40.64 223.52)
		)
		(stroke
			(width 0)
			(type default)
		)
	)
	(polyline
		(pts
			(xy 299.72 180.34) (xy 299.72 252.73)
		)
		(stroke
			(width 0)
			(type dash)
		)
	)
	(wire
		(pts
			(xy 130.81 44.45) (xy 130.81 49.53)
		)
		(stroke
			(width 0)
			(type default)
		)
	)
	(wire
		(pts
			(xy 179.07 49.53) (xy 179.07 54.61)
		)
		(stroke
			(width 0)
			(type default)
		)
	)
	(wire
		(pts
			(xy 193.04 245.11) (xy 193.04 246.38)
		)
		(stroke
			(width 0)
			(type default)
		)
	)
	(wire
		(pts
			(xy 163.83 227.33) (xy 163.83 228.6)
		)
		(stroke
			(width 0)
			(type default)
		)
	)
	(wire
		(pts
			(xy 99.06 233.68) (xy 99.06 237.49)
		)
		(stroke
			(width 0)
			(type default)
		)
	)
	(wire
		(pts
			(xy 266.7 257.81) (xy 274.32 257.81)
		)
		(stroke
			(width 0)
			(type default)
		)
	)
	(wire
		(pts
			(xy 179.07 48.26) (xy 179.07 49.53)
		)
		(stroke
			(width 0)
			(type default)
		)
	)
	(wire
		(pts
			(xy 138.43 49.53) (xy 139.7 49.53)
		)
		(stroke
			(width 0)
			(type default)
		)
	)
	(wire
		(pts
			(xy 334.01 219.71) (xy 334.01 220.98)
		)
		(stroke
			(width 0)
			(type default)
		)
	)
	(wire
		(pts
			(xy 236.22 214.63) (xy 236.22 217.17)
		)
		(stroke
			(width 0)
			(type default)
		)
	)
	(wire
		(pts
			(xy 170.18 162.56) (xy 172.72 162.56)
		)
		(stroke
			(width 0)
			(type default)
		)
	)
	(wire
		(pts
			(xy 199.39 129.54) (xy 199.39 134.62)
		)
		(stroke
			(width 0)
			(type default)
		)
	)
	(wire
		(pts
			(xy 170.18 166.37) (xy 170.18 162.56)
		)
		(stroke
			(width 0)
			(type default)
		)
	)
	(wire
		(pts
			(xy 372.11 64.77) (xy 372.11 66.04)
		)
		(stroke
			(width 0)
			(type default)
		)
	)
	(wire
		(pts
			(xy 227.33 224.79) (xy 236.22 224.79)
		)
		(stroke
			(width 0)
			(type default)
		)
	)
	(wire
		(pts
			(xy 248.92 62.23) (xy 248.92 60.96)
		)
		(stroke
			(width 0)
			(type default)
		)
	)
	(wire
		(pts
			(xy 245.11 243.84) (xy 245.11 251.46)
		)
		(stroke
			(width 0)
			(type default)
		)
	)
	(wire
		(pts
			(xy 363.22 55.88) (xy 372.11 55.88)
		)
		(stroke
			(width 0)
			(type default)
		)
	)
	(wire
		(pts
			(xy 290.83 62.23) (xy 290.83 63.5)
		)
		(stroke
			(width 0)
			(type default)
		)
	)
	(wire
		(pts
			(xy 139.7 137.16) (xy 139.7 138.43)
		)
		(stroke
			(width 0)
			(type default)
		)
	)
	(wire
		(pts
			(xy 123.19 44.45) (xy 124.46 44.45)
		)
		(stroke
			(width 0)
			(type default)
		)
	)
	(wire
		(pts
			(xy 254 243.84) (xy 254 254)
		)
		(stroke
			(width 0)
			(type default)
		)
	)
	(wire
		(pts
			(xy 93.98 233.68) (xy 99.06 233.68)
		)
		(stroke
			(width 0)
			(type default)
		)
	)
	(wire
		(pts
			(xy 104.14 134.62) (xy 91.44 134.62)
		)
		(stroke
			(width 0)
			(type default)
		)
	)
	(wire
		(pts
			(xy 294.64 134.62) (xy 299.72 134.62)
		)
		(stroke
			(width 0)
			(type default)
		)
	)
	(wire
		(pts
			(xy 48.26 124.46) (xy 48.26 127)
		)
		(stroke
			(width 0)
			(type default)
		)
	)
	(wire
		(pts
			(xy 88.9 246.38) (xy 91.44 246.38)
		)
		(stroke
			(width 0)
			(type default)
		)
	)
	(wire
		(pts
			(xy 227.33 196.85) (xy 227.33 199.39)
		)
		(stroke
			(width 0)
			(type default)
		)
	)
	(wire
		(pts
			(xy 90.17 54.61) (xy 105.41 54.61)
		)
		(stroke
			(width 0)
			(type default)
		)
	)
	(wire
		(pts
			(xy 83.82 154.94) (xy 83.82 149.86)
		)
		(stroke
			(width 0)
			(type default)
		)
	)
	(wire
		(pts
			(xy 259.08 265.43) (xy 265.43 265.43)
		)
		(stroke
			(width 0)
			(type default)
		)
	)
	(wire
		(pts
			(xy 372.11 59.69) (xy 372.11 55.88)
		)
		(stroke
			(width 0)
			(type default)
		)
	)
	(wire
		(pts
			(xy 245.11 251.46) (xy 257.81 251.46)
		)
		(stroke
			(width 0)
			(type default)
		)
	)
	(wire
		(pts
			(xy 104.14 60.96) (xy 104.14 62.23)
		)
		(stroke
			(width 0)
			(type default)
		)
	)
	(wire
		(pts
			(xy 236.22 201.93) (xy 236.22 209.55)
		)
		(stroke
			(width 0)
			(type default)
		)
	)
	(wire
		(pts
			(xy 90.17 67.31) (xy 90.17 69.85)
		)
		(stroke
			(width 0)
			(type default)
		)
	)
	(bus
		(pts
			(xy 311.15 77.47) (xy 311.15 80.01)
		)
		(stroke
			(width 0)
			(type default)
		)
	)
	(wire
		(pts
			(xy 312.42 81.28) (xy 323.85 81.28)
		)
		(stroke
			(width 0)
			(type default)
		)
	)
	(wire
		(pts
			(xy 236.22 248.92) (xy 257.81 248.92)
		)
		(stroke
			(width 0)
			(type default)
		)
	)
	(wire
		(pts
			(xy 248.92 52.07) (xy 248.92 54.61)
		)
		(stroke
			(width 0)
			(type default)
		)
	)
	(wire
		(pts
			(xy 139.7 49.53) (xy 139.7 50.8)
		)
		(stroke
			(width 0)
			(type default)
		)
	)
	(wire
		(pts
			(xy 69.85 242.57) (xy 69.85 243.84)
		)
		(stroke
			(width 0)
			(type default)
		)
	)
	(wire
		(pts
			(xy 254 257.81) (xy 254 254)
		)
		(stroke
			(width 0)
			(type default)
		)
	)
	(wire
		(pts
			(xy 355.6 76.2) (xy 355.6 78.74)
		)
		(stroke
			(width 0)
			(type default)
		)
	)
	(wire
		(pts
			(xy 52.07 237.49) (xy 52.07 223.52)
		)
		(stroke
			(width 0)
			(type default)
		)
	)
	(wire
		(pts
			(xy 189.23 154.94) (xy 194.31 154.94)
		)
		(stroke
			(width 0)
			(type default)
		)
	)
	(wire
		(pts
			(xy 139.7 57.15) (xy 139.7 58.42)
		)
		(stroke
			(width 0)
			(type default)
		)
	)
	(wire
		(pts
			(xy 245.11 265.43) (xy 245.11 251.46)
		)
		(stroke
			(width 0)
			(type default)
		)
	)
	(wire
		(pts
			(xy 254 149.86) (xy 265.43 149.86)
		)
		(stroke
			(width 0)
			(type default)
		)
	)
	(wire
		(pts
			(xy 276.86 134.62) (xy 279.4 134.62)
		)
		(stroke
			(width 0)
			(type default)
		)
	)
	(wire
		(pts
			(xy 236.22 248.92) (xy 236.22 256.54)
		)
		(stroke
			(width 0)
			(type default)
		)
	)
	(wire
		(pts
			(xy 179.07 63.5) (xy 179.07 59.69)
		)
		(stroke
			(width 0)
			(type default)
		)
	)
	(wire
		(pts
			(xy 300.99 69.85) (xy 300.99 66.04)
		)
		(stroke
			(width 0)
			(type default)
		)
	)
	(wire
		(pts
			(xy 163.83 157.48) (xy 172.72 157.48)
		)
		(stroke
			(width 0)
			(type default)
		)
	)
	(wire
		(pts
			(xy 309.88 142.24) (xy 309.88 143.51)
		)
		(stroke
			(width 0)
			(type default)
		)
	)
	(wire
		(pts
			(xy 76.2 223.52) (xy 76.2 224.79)
		)
		(stroke
			(width 0)
			(type default)
		)
	)
	(wire
		(pts
			(xy 393.7 53.34) (xy 393.7 55.88)
		)
		(stroke
			(width 0)
			(type default)
		)
	)
	(wire
		(pts
			(xy 334.01 218.44) (xy 334.01 219.71)
		)
		(stroke
			(width 0)
			(type default)
		)
	)
	(wire
		(pts
			(xy 372.11 66.04) (xy 377.19 66.04)
		)
		(stroke
			(width 0)
			(type default)
		)
	)
	(wire
		(pts
			(xy 340.36 78.74) (xy 340.36 80.01)
		)
		(stroke
			(width 0)
			(type default)
		)
	)
	(wire
		(pts
			(xy 44.45 245.11) (xy 53.34 245.11)
		)
		(stroke
			(width 0)
			(type default)
		)
	)
	(wire
		(pts
			(xy 257.81 130.81) (xy 266.7 130.81)
		)
		(stroke
			(width 0)
			(type default)
		)
	)
	(wire
		(pts
			(xy 372.11 55.88) (xy 373.38 55.88)
		)
		(stroke
			(width 0)
			(type default)
		)
	)
	(wire
		(pts
			(xy 48.26 223.52) (xy 52.07 223.52)
		)
		(stroke
			(width 0)
			(type default)
		)
	)
	(wire
		(pts
			(xy 228.6 52.07) (xy 228.6 54.61)
		)
		(stroke
			(width 0)
			(type default)
		)
	)
	(wire
		(pts
			(xy 358.14 55.88) (xy 358.14 60.96)
		)
		(stroke
			(width 0)
			(type default)
		)
	)
	(wire
		(pts
			(xy 377.19 66.04) (xy 377.19 69.85)
		)
		(stroke
			(width 0)
			(type default)
		)
	)
	(wire
		(pts
			(xy 99.06 233.68) (xy 99.06 231.14)
		)
		(stroke
			(width 0)
			(type default)
		)
	)
	(wire
		(pts
			(xy 257.81 52.07) (xy 257.81 55.88)
		)
		(stroke
			(width 0)
			(type default)
		)
	)
	(bus
		(pts
			(xy 162.56 153.67) (xy 162.56 156.21)
		)
		(stroke
			(width 0)
			(type default)
		)
	)
	(wire
		(pts
			(xy 322.58 55.88) (xy 327.66 55.88)
		)
		(stroke
			(width 0)
			(type default)
		)
	)
	(wire
		(pts
			(xy 227.33 199.39) (xy 257.81 199.39)
		)
		(stroke
			(width 0)
			(type default)
		)
	)
	(wire
		(pts
			(xy 52.07 223.52) (xy 58.42 223.52)
		)
		(stroke
			(width 0)
			(type default)
		)
	)
	(bus
		(pts
			(xy 162.56 153.67) (xy 161.29 152.4)
		)
		(stroke
			(width 0)
			(type default)
		)
	)
	(wire
		(pts
			(xy 76.2 242.57) (xy 76.2 241.3)
		)
		(stroke
			(width 0)
			(type default)
		)
	)
	(wire
		(pts
			(xy 300.99 55.88) (xy 300.99 60.96)
		)
		(stroke
			(width 0)
			(type default)
		)
	)
	(wire
		(pts
			(xy 346.71 55.88) (xy 358.14 55.88)
		)
		(stroke
			(width 0)
			(type default)
		)
	)
	(wire
		(pts
			(xy 68.58 237.49) (xy 69.85 237.49)
		)
		(stroke
			(width 0)
			(type default)
		)
	)
	(wire
		(pts
			(xy 257.81 129.54) (xy 257.81 130.81)
		)
		(stroke
			(width 0)
			(type default)
		)
	)
	(wire
		(pts
			(xy 323.85 86.36) (xy 321.31 86.36)
		)
		(stroke
			(width 0)
			(type default)
		)
	)
	(wire
		(pts
			(xy 181.61 129.54) (xy 189.23 129.54)
		)
		(stroke
			(width 0)
			(type default)
		)
	)
	(wire
		(pts
			(xy 245.11 224.79) (xy 254 224.79)
		)
		(stroke
			(width 0)
			(type default)
		)
	)
	(wire
		(pts
			(xy 280.67 243.84) (xy 280.67 246.38)
		)
		(stroke
			(width 0)
			(type default)
		)
	)
	(wire
		(pts
			(xy 63.5 223.52) (xy 68.58 223.52)
		)
		(stroke
			(width 0)
			(type default)
		)
	)
	(wire
		(pts
			(xy 63.5 154.94) (xy 66.04 154.94)
		)
		(stroke
			(width 0)
			(type default)
		)
	)
	(polyline
		(pts
			(xy 223.52 96.52) (xy 223.52 180.34)
		)
		(stroke
			(width 0)
			(type dash)
		)
	)
	(wire
		(pts
			(xy 138.43 129.54) (xy 139.7 129.54)
		)
		(stroke
			(width 0)
			(type default)
		)
	)
	(wire
		(pts
			(xy 152.4 242.57) (xy 158.75 242.57)
		)
		(stroke
			(width 0)
			(type default)
		)
	)
	(wire
		(pts
			(xy 339.09 73.66) (xy 340.36 73.66)
		)
		(stroke
			(width 0)
			(type default)
		)
	)
	(wire
		(pts
			(xy 52.07 254) (xy 52.07 250.19)
		)
		(stroke
			(width 0)
			(type default)
		)
	)
	(wire
		(pts
			(xy 33.02 223.52) (xy 35.56 223.52)
		)
		(stroke
			(width 0)
			(type default)
		)
	)
	(wire
		(pts
			(xy 340.36 78.74) (xy 345.44 78.74)
		)
		(stroke
			(width 0)
			(type default)
		)
	)
	(wire
		(pts
			(xy 173.99 240.03) (xy 171.45 240.03)
		)
		(stroke
			(width 0)
			(type default)
		)
	)
	(wire
		(pts
			(xy 187.96 162.56) (xy 189.23 162.56)
		)
		(stroke
			(width 0)
			(type default)
		)
	)
	(wire
		(pts
			(xy 99.06 49.53) (xy 105.41 49.53)
		)
		(stroke
			(width 0)
			(type default)
		)
	)
	(polyline
		(pts
			(xy 214.63 180.34) (xy 214.63 284.48)
		)
		(stroke
			(width 0)
			(type dash)
		)
	)
	(wire
		(pts
			(xy 201.93 240.03) (xy 198.12 240.03)
		)
		(stroke
			(width 0)
			(type default)
		)
	)
	(wire
		(pts
			(xy 309.88 140.97) (xy 309.88 142.24)
		)
		(stroke
			(width 0)
			(type default)
		)
	)
	(wire
		(pts
			(xy 123.19 54.61) (xy 129.54 54.61)
		)
		(stroke
			(width 0)
			(type default)
		)
	)
	(wire
		(pts
			(xy 280.67 262.89) (xy 280.67 271.78)
		)
		(stroke
			(width 0)
			(type default)
		)
	)
	(wire
		(pts
			(xy 93.98 223.52) (xy 95.25 223.52)
		)
		(stroke
			(width 0)
			(type default)
		)
	)
	(wire
		(pts
			(xy 52.07 247.65) (xy 53.34 247.65)
		)
		(stroke
			(width 0)
			(type default)
		)
	)
	(wire
		(pts
			(xy 149.86 143.51) (xy 149.86 139.7)
		)
		(stroke
			(width 0)
			(type default)
		)
	)
	(wire
		(pts
			(xy 236.22 201.93) (xy 257.81 201.93)
		)
		(stroke
			(width 0)
			(type default)
		)
	)
	(wire
		(pts
			(xy 228.6 50.8) (xy 228.6 52.07)
		)
		(stroke
			(width 0)
			(type default)
		)
	)
	(wire
		(pts
			(xy 191.77 245.11) (xy 193.04 245.11)
		)
		(stroke
			(width 0)
			(type default)
		)
	)
	(wire
		(pts
			(xy 91.44 134.62) (xy 83.82 134.62)
		)
		(stroke
			(width 0)
			(type default)
		)
	)
	(wire
		(pts
			(xy 123.19 124.46) (xy 124.46 124.46)
		)
		(stroke
			(width 0)
			(type default)
		)
	)
	(wire
		(pts
			(xy 340.36 55.88) (xy 340.36 73.66)
		)
		(stroke
			(width 0)
			(type default)
		)
	)
	(wire
		(pts
			(xy 276.86 130.81) (xy 276.86 134.62)
		)
		(stroke
			(width 0)
			(type default)
		)
	)
	(wire
		(pts
			(xy 248.92 60.96) (xy 260.35 60.96)
		)
		(stroke
			(width 0)
			(type default)
		)
	)
	(wire
		(pts
			(xy 104.14 134.62) (xy 104.14 135.89)
		)
		(stroke
			(width 0)
			(type default)
		)
	)
	(wire
		(pts
			(xy 160.02 129.54) (xy 160.02 134.62)
		)
		(stroke
			(width 0)
			(type default)
		)
	)
	(wire
		(pts
			(xy 149.86 129.54) (xy 160.02 129.54)
		)
		(stroke
			(width 0)
			(type default)
		)
	)
	(wire
		(pts
			(xy 339.09 78.74) (xy 340.36 78.74)
		)
		(stroke
			(width 0)
			(type default)
		)
	)
	(wire
		(pts
			(xy 85.09 246.38) (xy 88.9 246.38)
		)
		(stroke
			(width 0)
			(type default)
		)
	)
	(wire
		(pts
			(xy 93.98 232.41) (xy 93.98 233.68)
		)
		(stroke
			(width 0)
			(type default)
		)
	)
	(wire
		(pts
			(xy 344.17 222.25) (xy 344.17 219.71)
		)
		(stroke
			(width 0)
			(type default)
		)
	)
	(wire
		(pts
			(xy 161.29 245.11) (xy 161.29 248.92)
		)
		(stroke
			(width 0)
			(type default)
		)
	)
	(wire
		(pts
			(xy 254 207.01) (xy 254 209.55)
		)
		(stroke
			(width 0)
			(type default)
		)
	)
	(wire
		(pts
			(xy 254 196.85) (xy 254 207.01)
		)
		(stroke
			(width 0)
			(type default)
		)
	)
	(wire
		(pts
			(xy 227.33 214.63) (xy 227.33 217.17)
		)
		(stroke
			(width 0)
			(type default)
		)
	)
	(wire
		(pts
			(xy 91.44 147.32) (xy 105.41 147.32)
		)
		(stroke
			(width 0)
			(type default)
		)
	)
	(polyline
		(pts
			(xy 12.7 96.52) (xy 223.52 96.52)
		)
		(stroke
			(width 0)
			(type dash)
		)
	)
	(wire
		(pts
			(xy 68.58 250.19) (xy 69.85 250.19)
		)
		(stroke
			(width 0)
			(type default)
		)
	)
	(wire
		(pts
			(xy 245.11 214.63) (xy 245.11 217.17)
		)
		(stroke
			(width 0)
			(type default)
		)
	)
	(wire
		(pts
			(xy 129.54 137.16) (xy 139.7 137.16)
		)
		(stroke
			(width 0)
			(type default)
		)
	)
	(wire
		(pts
			(xy 163.83 226.06) (xy 163.83 227.33)
		)
		(stroke
			(width 0)
			(type default)
		)
	)
	(wire
		(pts
			(xy 367.03 222.25) (xy 367.03 226.06)
		)
		(stroke
			(width 0)
			(type default)
		)
	)
	(wire
		(pts
			(xy 63.5 137.16) (xy 68.58 137.16)
		)
		(stroke
			(width 0)
			(type default)
		)
	)
	(wire
		(pts
			(xy 76.2 137.16) (xy 76.2 144.78)
		)
		(stroke
			(width 0)
			(type default)
		)
	)
	(wire
		(pts
			(xy 172.72 160.02) (xy 171.45 160.02)
		)
		(stroke
			(width 0)
			(type default)
		)
	)
	(wire
		(pts
			(xy 334.01 219.71) (xy 344.17 219.71)
		)
		(stroke
			(width 0)
			(type default)
		)
	)
	(wire
		(pts
			(xy 73.66 129.54) (xy 76.2 129.54)
		)
		(stroke
			(width 0)
			(type default)
		)
	)
	(wire
		(pts
			(xy 344.17 134.62) (xy 351.79 134.62)
		)
		(stroke
			(width 0)
			(type default)
		)
	)
	(wire
		(pts
			(xy 58.42 124.46) (xy 58.42 127)
		)
		(stroke
			(width 0)
			(type default)
		)
	)
	(wire
		(pts
			(xy 130.81 124.46) (xy 130.81 129.54)
		)
		(stroke
			(width 0)
			(type default)
		)
	)
	(wire
		(pts
			(xy 332.74 55.88) (xy 340.36 55.88)
		)
		(stroke
			(width 0)
			(type default)
		)
	)
	(wire
		(pts
			(xy 236.22 243.84) (xy 236.22 248.92)
		)
		(stroke
			(width 0)
			(type default)
		)
	)
	(wire
		(pts
			(xy 149.86 49.53) (xy 149.86 54.61)
		)
		(stroke
			(width 0)
			(type default)
		)
	)
	(wire
		(pts
			(xy 236.22 271.78) (xy 254 271.78)
		)
		(stroke
			(width 0)
			(type default)
		)
	)
	(wire
		(pts
			(xy 171.45 129.54) (xy 171.45 149.86)
		)
		(stroke
			(width 0)
			(type default)
		)
	)
	(wire
		(pts
			(xy 77.47 44.45) (xy 77.47 46.99)
		)
		(stroke
			(width 0)
			(type default)
		)
	)
	(wire
		(pts
			(xy 170.18 248.92) (xy 170.18 245.11)
		)
		(stroke
			(width 0)
			(type default)
		)
	)
	(wire
		(pts
			(xy 172.72 49.53) (xy 179.07 49.53)
		)
		(stroke
			(width 0)
			(type default)
		)
	)
	(wire
		(pts
			(xy 278.13 144.78) (xy 279.4 144.78)
		)
		(stroke
			(width 0)
			(type default)
		)
	)
	(wire
		(pts
			(xy 271.78 251.46) (xy 271.78 260.35)
		)
		(stroke
			(width 0)
			(type default)
		)
	)
	(wire
		(pts
			(xy 279.4 207.01) (xy 276.86 207.01)
		)
		(stroke
			(width 0)
			(type default)
		)
	)
	(wire
		(pts
			(xy 123.19 134.62) (xy 129.54 134.62)
		)
		(stroke
			(width 0)
			(type default)
		)
	)
	(wire
		(pts
			(xy 129.54 57.15) (xy 139.7 57.15)
		)
		(stroke
			(width 0)
			(type default)
		)
	)
	(wire
		(pts
			(xy 271.78 271.78) (xy 280.67 271.78)
		)
		(stroke
			(width 0)
			(type default)
		)
	)
	(wire
		(pts
			(xy 388.62 218.44) (xy 388.62 219.71)
		)
		(stroke
			(width 0)
			(type default)
		)
	)
	(wire
		(pts
			(xy 76.2 129.54) (xy 105.41 129.54)
		)
		(stroke
			(width 0)
			(type default)
		)
	)
	(wire
		(pts
			(xy 199.39 128.27) (xy 199.39 129.54)
		)
		(stroke
			(width 0)
			(type default)
		)
	)
	(wire
		(pts
			(xy 69.85 223.52) (xy 69.85 237.49)
		)
		(stroke
			(width 0)
			(type default)
		)
	)
	(wire
		(pts
			(xy 76.2 223.52) (xy 93.98 223.52)
		)
		(stroke
			(width 0)
			(type default)
		)
	)
	(wire
		(pts
			(xy 321.31 86.36) (xy 321.31 78.74)
		)
		(stroke
			(width 0)
			(type default)
		)
	)
	(wire
		(pts
			(xy 271.78 237.49) (xy 280.67 237.49)
		)
		(stroke
			(width 0)
			(type default)
		)
	)
	(wire
		(pts
			(xy 91.44 144.78) (xy 91.44 147.32)
		)
		(stroke
			(width 0)
			(type default)
		)
	)
	(wire
		(pts
			(xy 67.31 44.45) (xy 67.31 46.99)
		)
		(stroke
			(width 0)
			(type default)
		)
	)
	(wire
		(pts
			(xy 365.76 82.55) (xy 368.3 82.55)
		)
		(stroke
			(width 0)
			(type default)
		)
	)
	(wire
		(pts
			(xy 104.14 140.97) (xy 104.14 142.24)
		)
		(stroke
			(width 0)
			(type default)
		)
	)
	(wire
		(pts
			(xy 48.26 123.19) (xy 48.26 124.46)
		)
		(stroke
			(width 0)
			(type default)
		)
	)
	(wire
		(pts
			(xy 165.1 163.83) (xy 165.1 166.37)
		)
		(stroke
			(width 0)
			(type default)
		)
	)
	(wire
		(pts
			(xy 365.76 78.74) (xy 368.3 78.74)
		)
		(stroke
			(width 0)
			(type default)
		)
	)
	(wire
		(pts
			(xy 160.02 49.53) (xy 160.02 54.61)
		)
		(stroke
			(width 0)
			(type default)
		)
	)
	(wire
		(pts
			(xy 279.4 142.24) (xy 278.13 142.24)
		)
		(stroke
			(width 0)
			(type default)
		)
	)
	(wire
		(pts
			(xy 129.54 134.62) (xy 129.54 137.16)
		)
		(stroke
			(width 0)
			(type default)
		)
	)
	(wire
		(pts
			(xy 290.83 55.88) (xy 290.83 57.15)
		)
		(stroke
			(width 0)
			(type default)
		)
	)
	(wire
		(pts
			(xy 104.14 142.24) (xy 105.41 142.24)
		)
		(stroke
			(width 0)
			(type default)
		)
	)
	(wire
		(pts
			(xy 83.82 134.62) (xy 83.82 144.78)
		)
		(stroke
			(width 0)
			(type default)
		)
	)
	(wire
		(pts
			(xy 69.85 250.19) (xy 69.85 254)
		)
		(stroke
			(width 0)
			(type default)
		)
	)
	(wire
		(pts
			(xy 91.44 134.62) (xy 91.44 139.7)
		)
		(stroke
			(width 0)
			(type default)
		)
	)
	(wire
		(pts
			(xy 91.44 147.32) (xy 91.44 149.86)
		)
		(stroke
			(width 0)
			(type default)
		)
	)
	(wire
		(pts
			(xy 171.45 160.02) (xy 171.45 167.64)
		)
		(stroke
			(width 0)
			(type default)
		)
	)
	(wire
		(pts
			(xy 149.86 49.53) (xy 160.02 49.53)
		)
		(stroke
			(width 0)
			(type default)
		)
	)
	(wire
		(pts
			(xy 311.15 55.88) (xy 322.58 55.88)
		)
		(stroke
			(width 0)
			(type default)
		)
	)
	(wire
		(pts
			(xy 330.2 134.62) (xy 330.2 139.7)
		)
		(stroke
			(width 0)
			(type default)
		)
	)
	(wire
		(pts
			(xy 124.46 64.77) (xy 124.46 67.31)
		)
		(stroke
			(width 0)
			(type default)
		)
	)
	(bus
		(pts
			(xy 151.13 152.4) (xy 161.29 152.4)
		)
		(stroke
			(width 0)
			(type default)
		)
	)
	(wire
		(pts
			(xy 124.46 147.32) (xy 123.19 147.32)
		)
		(stroke
			(width 0)
			(type default)
		)
	)
	(wire
		(pts
			(xy 170.18 245.11) (xy 173.99 245.11)
		)
		(stroke
			(width 0)
			(type default)
		)
	)
	(wire
		(pts
			(xy 257.81 138.43) (xy 257.81 140.97)
		)
		(stroke
			(width 0)
			(type default)
		)
	)
	(wire
		(pts
			(xy 123.19 129.54) (xy 130.81 129.54)
		)
		(stroke
			(width 0)
			(type default)
		)
	)
	(wire
		(pts
			(xy 160.02 129.54) (xy 171.45 129.54)
		)
		(stroke
			(width 0)
			(type default)
		)
	)
	(wire
		(pts
			(xy 245.11 196.85) (xy 245.11 204.47)
		)
		(stroke
			(width 0)
			(type default)
		)
	)
	(wire
		(pts
			(xy 311.15 55.88) (xy 300.99 55.88)
		)
		(stroke
			(width 0)
			(type default)
		)
	)
	(wire
		(pts
			(xy 266.7 130.81) (xy 276.86 130.81)
		)
		(stroke
			(width 0)
			(type default)
		)
	)
	(wire
		(pts
			(xy 58.42 124.46) (xy 105.41 124.46)
		)
		(stroke
			(width 0)
			(type default)
		)
	)
	(wire
		(pts
			(xy 34.29 226.06) (xy 34.29 227.33)
		)
		(stroke
			(width 0)
			(type default)
		)
	)
	(bus
		(pts
			(xy 43.18 241.3) (xy 41.91 240.03)
		)
		(stroke
			(width 0)
			(type default)
		)
	)
	(wire
		(pts
			(xy 271.78 243.84) (xy 271.78 246.38)
		)
		(stroke
			(width 0)
			(type default)
		)
	)
	(wire
		(pts
			(xy 254 207.01) (xy 257.81 207.01)
		)
		(stroke
			(width 0)
			(type default)
		)
	)
	(polyline
		(pts
			(xy 135.89 180.34) (xy 135.89 284.48)
		)
		(stroke
			(width 0)
			(type dash)
		)
	)
	(wire
		(pts
			(xy 236.22 269.24) (xy 236.22 271.78)
		)
		(stroke
			(width 0)
			(type default)
		)
	)
	(wire
		(pts
			(xy 393.7 55.88) (xy 401.32 55.88)
		)
		(stroke
			(width 0)
			(type default)
		)
	)
	(wire
		(pts
			(xy 401.32 53.34) (xy 401.32 55.88)
		)
		(stroke
			(width 0)
			(type default)
		)
	)
	(wire
		(pts
			(xy 320.04 134.62) (xy 309.88 134.62)
		)
		(stroke
			(width 0)
			(type default)
		)
	)
	(wire
		(pts
			(xy 90.17 54.61) (xy 90.17 59.69)
		)
		(stroke
			(width 0)
			(type default)
		)
	)
	(wire
		(pts
			(xy 68.58 223.52) (xy 69.85 223.52)
		)
		(stroke
			(width 0)
			(type default)
		)
	)
	(wire
		(pts
			(xy 280.67 251.46) (xy 280.67 252.73)
		)
		(stroke
			(width 0)
			(type default)
		)
	)
	(wire
		(pts
			(xy 330.2 148.59) (xy 330.2 144.78)
		)
		(stroke
			(width 0)
			(type default)
		)
	)
	(wire
		(pts
			(xy 300.99 55.88) (xy 290.83 55.88)
		)
		(stroke
			(width 0)
			(type default)
		)
	)
	(wire
		(pts
			(xy 266.7 130.81) (xy 266.7 133.35)
		)
		(stroke
			(width 0)
			(type default)
		)
	)
	(wire
		(pts
			(xy 90.17 54.61) (xy 82.55 54.61)
		)
		(stroke
			(width 0)
			(type default)
		)
	)
	(wire
		(pts
			(xy 322.58 55.88) (xy 322.58 73.66)
		)
		(stroke
			(width 0)
			(type default)
		)
	)
	(wire
		(pts
			(xy 116.84 223.52) (xy 116.84 220.98)
		)
		(stroke
			(width 0)
			(type default)
		)
	)
	(wire
		(pts
			(xy 67.31 43.18) (xy 67.31 44.45)
		)
		(stroke
			(width 0)
			(type default)
		)
	)
	(wire
		(pts
			(xy 139.7 55.88) (xy 139.7 57.15)
		)
		(stroke
			(width 0)
			(type default)
		)
	)
	(wire
		(pts
			(xy 189.23 129.54) (xy 189.23 149.86)
		)
		(stroke
			(width 0)
			(type default)
		)
	)
	(wire
		(pts
			(xy 377.19 85.09) (xy 377.19 82.55)
		)
		(stroke
			(width 0)
			(type default)
		)
	)
	(bus
		(pts
			(xy 43.18 241.3) (xy 43.18 243.84)
		)
		(stroke
			(width 0)
			(type default)
		)
	)
	(wire
		(pts
			(xy 227.33 261.62) (xy 227.33 264.16)
		)
		(stroke
			(width 0)
			(type default)
		)
	)
	(wire
		(pts
			(xy 270.51 149.86) (xy 274.32 149.86)
		)
		(stroke
			(width 0)
			(type default)
		)
	)
	(polyline
		(pts
			(xy 406.4 180.34) (xy 223.52 180.34)
		)
		(stroke
			(width 0)
			(type dash)
		)
	)
	(wire
		(pts
			(xy 344.17 219.71) (xy 345.44 219.71)
		)
		(stroke
			(width 0)
			(type default)
		)
	)
	(wire
		(pts
			(xy 34.29 226.06) (xy 33.02 226.06)
		)
		(stroke
			(width 0)
			(type default)
		)
	)
	(wire
		(pts
			(xy 189.23 161.29) (xy 189.23 162.56)
		)
		(stroke
			(width 0)
			(type default)
		)
	)
	(wire
		(pts
			(xy 377.19 66.04) (xy 377.19 63.5)
		)
		(stroke
			(width 0)
			(type default)
		)
	)
	(wire
		(pts
			(xy 227.33 246.38) (xy 257.81 246.38)
		)
		(stroke
			(width 0)
			(type default)
		)
	)
	(wire
		(pts
			(xy 139.7 129.54) (xy 139.7 130.81)
		)
		(stroke
			(width 0)
			(type default)
		)
	)
	(wire
		(pts
			(xy 124.46 148.59) (xy 124.46 147.32)
		)
		(stroke
			(width 0)
			(type default)
		)
	)
	(wire
		(pts
			(xy 275.59 63.5) (xy 290.83 63.5)
		)
		(stroke
			(width 0)
			(type default)
		)
	)
	(wire
		(pts
			(xy 77.47 44.45) (xy 105.41 44.45)
		)
		(stroke
			(width 0)
			(type default)
		)
	)
	(wire
		(pts
			(xy 278.13 142.24) (xy 278.13 144.78)
		)
		(stroke
			(width 0)
			(type default)
		)
	)
	(wire
		(pts
			(xy 189.23 154.94) (xy 189.23 156.21)
		)
		(stroke
			(width 0)
			(type default)
		)
	)
	(wire
		(pts
			(xy 116.84 223.52) (xy 107.95 223.52)
		)
		(stroke
			(width 0)
			(type default)
		)
	)
	(wire
		(pts
			(xy 93.98 223.52) (xy 93.98 227.33)
		)
		(stroke
			(width 0)
			(type default)
		)
	)
	(wire
		(pts
			(xy 274.32 149.86) (xy 274.32 139.7)
		)
		(stroke
			(width 0)
			(type default)
		)
	)
	(wire
		(pts
			(xy 35.56 214.63) (xy 35.56 223.52)
		)
		(stroke
			(width 0)
			(type default)
		)
	)
	(wire
		(pts
			(xy 129.54 44.45) (xy 130.81 44.45)
		)
		(stroke
			(width 0)
			(type default)
		)
	)
	(wire
		(pts
			(xy 48.26 124.46) (xy 58.42 124.46)
		)
		(stroke
			(width 0)
			(type default)
		)
	)
	(wire
		(pts
			(xy 44.45 242.57) (xy 53.34 242.57)
		)
		(stroke
			(width 0)
			(type default)
		)
	)
	(wire
		(pts
			(xy 139.7 49.53) (xy 149.86 49.53)
		)
		(stroke
			(width 0)
			(type default)
		)
	)
	(wire
		(pts
			(xy 340.36 85.09) (xy 340.36 86.36)
		)
		(stroke
			(width 0)
			(type default)
		)
	)
	(wire
		(pts
			(xy 271.78 234.95) (xy 271.78 237.49)
		)
		(stroke
			(width 0)
			(type default)
		)
	)
	(wire
		(pts
			(xy 163.83 154.94) (xy 172.72 154.94)
		)
		(stroke
			(width 0)
			(type default)
		)
	)
	(wire
		(pts
			(xy 163.83 242.57) (xy 173.99 242.57)
		)
		(stroke
			(width 0)
			(type default)
		)
	)
	(wire
		(pts
			(xy 152.4 242.57) (xy 152.4 245.11)
		)
		(stroke
			(width 0)
			(type default)
		)
	)
	(bus
		(pts
			(xy 38.1 240.03) (xy 41.91 240.03)
		)
		(stroke
			(width 0)
			(type default)
		)
	)
	(wire
		(pts
			(xy 123.19 49.53) (xy 130.81 49.53)
		)
		(stroke
			(width 0)
			(type default)
		)
	)
	(wire
		(pts
			(xy 160.02 49.53) (xy 167.64 49.53)
		)
		(stroke
			(width 0)
			(type default)
		)
	)
	(wire
		(pts
			(xy 254 214.63) (xy 254 217.17)
		)
		(stroke
			(width 0)
			(type default)
		)
	)
	(wire
		(pts
			(xy 160.02 63.5) (xy 160.02 59.69)
		)
		(stroke
			(width 0)
			(type default)
		)
	)
	(wire
		(pts
			(xy 365.76 222.25) (xy 367.03 222.25)
		)
		(stroke
			(width 0)
			(type default)
		)
	)
	(wire
		(pts
			(xy 340.36 86.36) (xy 340.36 88.9)
		)
		(stroke
			(width 0)
			(type default)
		)
	)
	(wire
		(pts
			(xy 257.81 55.88) (xy 260.35 55.88)
		)
		(stroke
			(width 0)
			(type default)
		)
	)
	(wire
		(pts
			(xy 340.36 55.88) (xy 346.71 55.88)
		)
		(stroke
			(width 0)
			(type default)
		)
	)
	(wire
		(pts
			(xy 365.76 219.71) (xy 375.92 219.71)
		)
		(stroke
			(width 0)
			(type default)
		)
	)
	(wire
		(pts
			(xy 271.78 237.49) (xy 271.78 238.76)
		)
		(stroke
			(width 0)
			(type default)
		)
	)
	(polyline
		(pts
			(xy 406.4 96.52) (xy 223.52 96.52)
		)
		(stroke
			(width 0)
			(type dash)
		)
	)
	(wire
		(pts
			(xy 320.04 134.62) (xy 320.04 139.7)
		)
		(stroke
			(width 0)
			(type default)
		)
	)
	(wire
		(pts
			(xy 290.83 63.5) (xy 290.83 64.77)
		)
		(stroke
			(width 0)
			(type default)
		)
	)
	(wire
		(pts
			(xy 104.14 62.23) (xy 105.41 62.23)
		)
		(stroke
			(width 0)
			(type default)
		)
	)
	(wire
		(pts
			(xy 401.32 55.88) (xy 401.32 60.96)
		)
		(stroke
			(width 0)
			(type default)
		)
	)
	(wire
		(pts
			(xy 52.07 250.19) (xy 53.34 250.19)
		)
		(stroke
			(width 0)
			(type default)
		)
	)
	(wire
		(pts
			(xy 322.58 73.66) (xy 323.85 73.66)
		)
		(stroke
			(width 0)
			(type default)
		)
	)
	(wire
		(pts
			(xy 345.44 222.25) (xy 344.17 222.25)
		)
		(stroke
			(width 0)
			(type default)
		)
	)
	(wire
		(pts
			(xy 116.84 223.52) (xy 121.92 223.52)
		)
		(stroke
			(width 0)
			(type default)
		)
	)
	(wire
		(pts
			(xy 76.2 220.98) (xy 76.2 223.52)
		)
		(stroke
			(width 0)
			(type default)
		)
	)
	(wire
		(pts
			(xy 368.3 78.74) (xy 368.3 82.55)
		)
		(stroke
			(width 0)
			(type default)
		)
	)
	(wire
		(pts
			(xy 104.14 43.18) (xy 104.14 55.88)
		)
		(stroke
			(width 0)
			(type default)
		)
	)
	(wire
		(pts
			(xy 149.86 129.54) (xy 149.86 134.62)
		)
		(stroke
			(width 0)
			(type default)
		)
	)
	(wire
		(pts
			(xy 45.72 223.52) (xy 48.26 223.52)
		)
		(stroke
			(width 0)
			(type default)
		)
	)
	(wire
		(pts
			(xy 63.5 139.7) (xy 63.5 137.16)
		)
		(stroke
			(width 0)
			(type default)
		)
	)
	(wire
		(pts
			(xy 236.22 261.62) (xy 236.22 264.16)
		)
		(stroke
			(width 0)
			(type default)
		)
	)
	(wire
		(pts
			(xy 227.33 199.39) (xy 227.33 209.55)
		)
		(stroke
			(width 0)
			(type default)
		)
	)
	(wire
		(pts
			(xy 278.13 146.05) (xy 278.13 144.78)
		)
		(stroke
			(width 0)
			(type default)
		)
	)
	(wire
		(pts
			(xy 245.11 204.47) (xy 257.81 204.47)
		)
		(stroke
			(width 0)
			(type default)
		)
	)
	(wire
		(pts
			(xy 171.45 240.03) (xy 171.45 227.33)
		)
		(stroke
			(width 0)
			(type default)
		)
	)
	(wire
		(pts
			(xy 67.31 44.45) (xy 77.47 44.45)
		)
		(stroke
			(width 0)
			(type default)
		)
	)
	(wire
		(pts
			(xy 351.79 134.62) (xy 351.79 139.7)
		)
		(stroke
			(width 0)
			(type default)
		)
	)
	(wire
		(pts
			(xy 322.58 83.82) (xy 322.58 88.9)
		)
		(stroke
			(width 0)
			(type default)
		)
	)
	(wire
		(pts
			(xy 236.22 224.79) (xy 245.11 224.79)
		)
		(stroke
			(width 0)
			(type default)
		)
	)
	(wire
		(pts
			(xy 129.54 54.61) (xy 129.54 57.15)
		)
		(stroke
			(width 0)
			(type default)
		)
	)
	(wire
		(pts
			(xy 129.54 124.46) (xy 130.81 124.46)
		)
		(stroke
			(width 0)
			(type default)
		)
	)
	(wire
		(pts
			(xy 237.49 52.07) (xy 248.92 52.07)
		)
		(stroke
			(width 0)
			(type default)
		)
	)
	(polyline
		(pts
			(xy 12.7 180.34) (xy 223.52 180.34)
		)
		(stroke
			(width 0)
			(type dash)
		)
	)
	(wire
		(pts
			(xy 375.92 219.71) (xy 378.46 219.71)
		)
		(stroke
			(width 0)
			(type default)
		)
	)
	(wire
		(pts
			(xy 245.11 222.25) (xy 245.11 224.79)
		)
		(stroke
			(width 0)
			(type default)
		)
	)
	(wire
		(pts
			(xy 123.19 144.78) (xy 124.46 144.78)
		)
		(stroke
			(width 0)
			(type default)
		)
	)
	(wire
		(pts
			(xy 227.33 243.84) (xy 227.33 246.38)
		)
		(stroke
			(width 0)
			(type default)
		)
	)
	(wire
		(pts
			(xy 358.14 55.88) (xy 363.22 55.88)
		)
		(stroke
			(width 0)
			(type default)
		)
	)
	(wire
		(pts
			(xy 401.32 69.85) (xy 401.32 66.04)
		)
		(stroke
			(width 0)
			(type default)
		)
	)
	(wire
		(pts
			(xy 236.22 196.85) (xy 236.22 201.93)
		)
		(stroke
			(width 0)
			(type default)
		)
	)
	(wire
		(pts
			(xy 87.63 49.53) (xy 93.98 49.53)
		)
		(stroke
			(width 0)
			(type default)
		)
	)
	(wire
		(pts
			(xy 237.49 52.07) (xy 237.49 54.61)
		)
		(stroke
			(width 0)
			(type default)
		)
	)
	(wire
		(pts
			(xy 320.04 134.62) (xy 330.2 134.62)
		)
		(stroke
			(width 0)
			(type default)
		)
	)
	(wire
		(pts
			(xy 271.78 270.51) (xy 271.78 271.78)
		)
		(stroke
			(width 0)
			(type default)
		)
	)
	(wire
		(pts
			(xy 321.31 78.74) (xy 323.85 78.74)
		)
		(stroke
			(width 0)
			(type default)
		)
	)
	(wire
		(pts
			(xy 82.55 54.61) (xy 82.55 57.15)
		)
		(stroke
			(width 0)
			(type default)
		)
	)
	(polyline
		(pts
			(xy 223.52 12.7) (xy 223.52 96.52)
		)
		(stroke
			(width 0)
			(type dash)
		)
	)
	(wire
		(pts
			(xy 257.81 130.81) (xy 257.81 133.35)
		)
		(stroke
			(width 0)
			(type default)
		)
	)
	(wire
		(pts
			(xy 312.42 78.74) (xy 321.31 78.74)
		)
		(stroke
			(width 0)
			(type default)
		)
	)
	(wire
		(pts
			(xy 68.58 137.16) (xy 76.2 137.16)
		)
		(stroke
			(width 0)
			(type default)
		)
	)
	(wire
		(pts
			(xy 323.85 83.82) (xy 322.58 83.82)
		)
		(stroke
			(width 0)
			(type default)
		)
	)
	(wire
		(pts
			(xy 69.85 223.52) (xy 76.2 223.52)
		)
		(stroke
			(width 0)
			(type default)
		)
	)
	(wire
		(pts
			(xy 97.79 62.23) (xy 104.14 62.23)
		)
		(stroke
			(width 0)
			(type default)
		)
	)
	(wire
		(pts
			(xy 90.17 67.31) (xy 105.41 67.31)
		)
		(stroke
			(width 0)
			(type default)
		)
	)
	(wire
		(pts
			(xy 355.6 78.74) (xy 360.68 78.74)
		)
		(stroke
			(width 0)
			(type default)
		)
	)
	(label "I2C{I2C}"
		(at 151.13 152.4 0)
		(effects
			(font
				(size 1.27 1.27)
			)
			(justify left bottom)
		)
	)
	(label "I2C.SCL"
		(at 163.83 157.48 0)
		(effects
			(font
				(size 1.27 1.27)
			)
			(justify left bottom)
		)
	)
	(label "I2C.SCL"
		(at 44.45 245.11 0)
		(effects
			(font
				(size 1.27 1.27)
			)
			(justify left bottom)
		)
	)
	(label "I2C.SDA"
		(at 312.42 78.74 0)
		(effects
			(font
				(size 1.27 1.27)
			)
			(justify left bottom)
		)
	)
	(label "PG_{1V0}"
		(at 146.05 242.57 0)
		(effects
			(font
				(size 1.27 1.27)
			)
			(justify left bottom)
		)
	)
	(label "PG_{3V3}"
		(at 254 149.86 0)
		(effects
			(font
				(size 1.27 1.27)
			)
			(justify left bottom)
		)
	)
	(label "I2C.SDA"
		(at 44.45 242.57 0)
		(effects
			(font
				(size 1.27 1.27)
			)
			(justify left bottom)
		)
	)
	(label "I2C.SCL"
		(at 312.42 81.28 0)
		(effects
			(font
				(size 1.27 1.27)
			)
			(justify left bottom)
		)
	)
	(label "I2C{I2C}"
		(at 299.72 76.2 0)
		(effects
			(font
				(size 1.27 1.27)
			)
			(justify left bottom)
		)
	)
	(label "I2C.SDA"
		(at 163.83 154.94 0)
		(effects
			(font
				(size 1.27 1.27)
			)
			(justify left bottom)
		)
	)
	(label "PG_{3V3}"
		(at 97.79 142.24 0)
		(effects
			(font
				(size 1.27 1.27)
			)
			(justify left bottom)
		)
	)
	(label "PG_{1V0}"
		(at 97.79 62.23 0)
		(effects
			(font
				(size 1.27 1.27)
			)
			(justify left bottom)
		)
	)
	(hierarchical_label "PSON"
		(shape input)
		(at 63.5 154.94 180)
		(effects
			(font
				(size 1.27 1.27)
			)
			(justify right)
		)
	)
	(hierarchical_label "PWR_OK"
		(shape output)
		(at 201.93 240.03 0)
		(effects
			(font
				(size 1.27 1.27)
			)
			(justify left)
		)
	)
	(hierarchical_label "PSON"
		(shape input)
		(at 85.09 246.38 180)
		(effects
			(font
				(size 1.27 1.27)
			)
			(justify right)
		)
	)
	(hierarchical_label "I2C{I2C}"
		(shape input)
		(at 38.1 240.03 180)
		(effects
			(font
				(size 1.27 1.27)
			)
			(justify right)
		)
	)
	(hierarchical_label "~{RESET}"
		(shape input)
		(at 359.41 82.55 180)
		(effects
			(font
				(size 1.27 1.27)
			)
			(justify right)
		)
	)
	(symbol
		(lib_id "antmicroResistors0402:R_100k_0402")
		(at 372.11 64.77 90)
		(unit 1)
		(exclude_from_sim no)
		(in_bom yes)
		(on_board yes)
		(dnp no)
		(property "Reference" "R118"
			(at 370.84 60.96 90)
			(effects
				(font
					(size 1.27 1.27)
					(thickness 0.15)
				)
				(justify left)
			)
		)
		(property "Value" "R_100k_0402"
			(at 384.81 44.45 0)
			(effects
				(font
					(size 1.27 1.27)
					(thickness 0.15)
				)
				(justify left bottom)
				(hide yes)
			)
		)
		(property "Footprint" "antmicro-footprints:R_0402_1005Metric"
			(at 387.35 44.45 0)
			(effects
				(font
					(size 1.27 1.27)
					(thickness 0.15)
				)
				(justify left bottom)
				(hide yes)
			)
		)
		(property "Datasheet" "https://www.bourns.com/docs/product-datasheets/cr.pdf"
			(at 389.89 44.45 0)
			(effects
				(font
					(size 1.27 1.27)
					(thickness 0.15)
				)
				(justify left bottom)
				(hide yes)
			)
		)
		(property "Description" ""
			(at 372.11 64.77 0)
			(effects
				(font
					(size 1.27 1.27)
				)
				(hide yes)
			)
		)
		(property "MPN" "CR0402-FX-1003GLF"
			(at 392.43 44.45 0)
			(effects
				(font
					(size 1.27 1.27)
					(thickness 0.15)
				)
				(justify left bottom)
				(hide yes)
			)
		)
		(property "Manufacturer" "Bourns"
			(at 394.97 44.45 0)
			(effects
				(font
					(size 1.27 1.27)
					(thickness 0.15)
				)
				(justify left bottom)
				(hide yes)
			)
		)
		(property "License" "Apache-2.0"
			(at 397.51 44.45 0)
			(effects
				(font
					(size 1.27 1.27)
					(thickness 0.15)
				)
				(justify left bottom)
				(hide yes)
			)
		)
		(property "Author" "Antmicro"
			(at 400.05 44.45 0)
			(effects
				(font
					(size 1.27 1.27)
					(thickness 0.15)
				)
				(justify left bottom)
				(hide yes)
			)
		)
		(property "Val" "100k"
			(at 370.84 63.5 90)
			(effects
				(font
					(size 1.27 1.27)
					(thickness 0.15)
				)
				(justify left)
			)
		)
		(property "Tolerance" "1%"
			(at 382.27 44.45 0)
			(effects
				(font
					(size 1.27 1.27)
				)
				(justify left bottom)
				(hide yes)
			)
		)
		(property "Public" "False"
			(at 402.59 44.45 0)
			(effects
				(font
					(size 1.27 1.27)
				)
				(justify left bottom)
				(hide yes)
			)
		)
		(pin "1"
		)
		(pin "2"
		)
		(instances
			(project "com-express-7-baseboard"
				(path ""
					(reference "R118")
					(unit 1)
				)
			)
		)
	)
	(symbol
		(lib_id "antmicroResistors0402:R_15k_0402")
		(at 309.88 148.59 90)
		(unit 1)
		(exclude_from_sim no)
		(in_bom yes)
		(on_board yes)
		(dnp no)
		(fields_autoplaced yes)
		(property "Reference" "R112"
			(at 312.42 144.7799 90)
			(effects
				(font
					(size 1.27 1.27)
					(thickness 0.15)
				)
				(justify right)
			)
		)
		(property "Value" "R_15k_0402"
			(at 322.58 128.27 0)
			(effects
				(font
					(size 1.27 1.27)
					(thickness 0.15)
				)
				(justify left bottom)
				(hide yes)
			)
		)
		(property "Footprint" "antmicro-footprints:R_0402_1005Metric"
			(at 325.12 128.27 0)
			(effects
				(font
					(size 1.27 1.27)
					(thickness 0.15)
				)
				(justify left bottom)
				(hide yes)
			)
		)
		(property "Datasheet" "https://www.bourns.com/docs/product-datasheets/cr.pdf"
			(at 327.66 128.27 0)
			(effects
				(font
					(size 1.27 1.27)
					(thickness 0.15)
				)
				(justify left bottom)
				(hide yes)
			)
		)
		(property "Description" ""
			(at 309.88 148.59 0)
			(effects
				(font
					(size 1.27 1.27)
				)
				(hide yes)
			)
		)
		(property "MPN" "CR0402-FX-1502GLF"
			(at 330.2 128.27 0)
			(effects
				(font
					(size 1.27 1.27)
					(thickness 0.15)
				)
				(justify left bottom)
				(hide yes)
			)
		)
		(property "Manufacturer" "Bourns"
			(at 332.74 128.27 0)
			(effects
				(font
					(size 1.27 1.27)
					(thickness 0.15)
				)
				(justify left bottom)
				(hide yes)
			)
		)
		(property "License" "Apache-2.0"
			(at 335.28 128.27 0)
			(effects
				(font
					(size 1.27 1.27)
					(thickness 0.15)
				)
				(justify left bottom)
				(hide yes)
			)
		)
		(property "Author" "Antmicro"
			(at 337.82 128.27 0)
			(effects
				(font
					(size 1.27 1.27)
					(thickness 0.15)
				)
				(justify left bottom)
				(hide yes)
			)
		)
		(property "Val" "15k"
			(at 312.42 147.3199 90)
			(effects
				(font
					(size 1.27 1.27)
					(thickness 0.15)
				)
				(justify right)
			)
		)
		(property "Tolerance" "1%"
			(at 320.04 128.27 0)
			(effects
				(font
					(size 1.27 1.27)
				)
				(justify left bottom)
				(hide yes)
			)
		)
		(property "Public" "False"
			(at 340.36 128.27 0)
			(effects
				(font
					(size 1.27 1.27)
				)
				(justify left bottom)
				(hide yes)
			)
		)
		(pin "2"
		)
		(pin "1"
		)
		(instances
			(project "com-express-7-baseboard"
				(path ""
					(reference "R112")
					(unit 1)
				)
			)
		)
	)
	(symbol
		(lib_id "antmicroFixedInductors:L_1u8_14A_Coilcraft-XAL6030")
		(at 133.35 129.54 0)
		(unit 1)
		(exclude_from_sim no)
		(in_bom yes)
		(on_board yes)
		(dnp no)
		(fields_autoplaced yes)
		(property "Reference" "L2"
			(at 135.89 124.46 0)
			(effects
				(font
					(size 1.27 1.27)
					(thickness 0.15)
				)
			)
		)
		(property "Value" "L_1u8_14A_Coilcraft-XAL6030"
			(at 148.59 139.7 0)
			(effects
				(font
					(size 1.27 1.27)
					(thickness 0.15)
				)
				(justify left bottom)
				(hide yes)
			)
		)
		(property "Footprint" "antmicro-footprints:L_Coilcraft-XAL6030"
			(at 148.59 142.24 0)
			(effects
				(font
					(size 1.27 1.27)
					(thickness 0.15)
				)
				(justify left bottom)
				(hide yes)
			)
		)
		(property "Datasheet" "https://www.mouser.com/datasheet/2/597/xal60xx-270658.pdf"
			(at 148.59 144.78 0)
			(effects
				(font
					(size 1.27 1.27)
					(thickness 0.15)
				)
				(justify left bottom)
				(hide yes)
			)
		)
		(property "Description" ""
			(at 133.35 129.54 0)
			(effects
				(font
					(size 1.27 1.27)
				)
				(hide yes)
			)
		)
		(property "Manufacturer" "Coilcraft"
			(at 148.59 147.32 0)
			(effects
				(font
					(size 1.27 1.27)
					(thickness 0.15)
				)
				(justify left bottom)
				(hide yes)
			)
		)
		(property "MPN" "XAL6030-182MEC"
			(at 148.59 149.86 0)
			(effects
				(font
					(size 1.27 1.27)
					(thickness 0.15)
				)
				(justify left bottom)
				(hide yes)
			)
		)
		(property "ISat" "18.2 A"
			(at 148.59 152.4 0)
			(effects
				(font
					(size 1.27 1.27)
					(thickness 0.15)
				)
				(justify left bottom)
				(hide yes)
			)
		)
		(property "IMax" "14 A"
			(at 148.59 154.94 0)
			(effects
				(font
					(size 1.27 1.27)
					(thickness 0.15)
				)
				(justify left bottom)
				(hide yes)
			)
		)
		(property "Size" "6.36x6.56"
			(at 148.59 157.48 0)
			(effects
				(font
					(size 1.27 1.27)
					(thickness 0.15)
				)
				(justify left bottom)
				(hide yes)
			)
		)
		(property "Val" "1.8u/14A"
			(at 135.89 127 0)
			(effects
				(font
					(size 1.27 1.27)
					(thickness 0.15)
				)
			)
		)
		(property "Author" "Antmicro"
			(at 148.59 160.02 0)
			(effects
				(font
					(size 1.27 1.27)
					(thickness 0.15)
				)
				(justify left bottom)
				(hide yes)
			)
		)
		(property "License" "Apache-2.0"
			(at 148.59 162.56 0)
			(effects
				(font
					(size 1.27 1.27)
					(thickness 0.15)
				)
				(justify left bottom)
				(hide yes)
			)
		)
		(property "Public" "False"
			(at 147.32 160.02 0)
			(effects
				(font
					(size 1.27 1.27)
				)
				(justify left bottom)
				(hide yes)
			)
		)
		(pin "1"
		)
		(pin "2"
		)
		(instances
			(project "com-express-7-baseboard"
				(path ""
					(reference "L2")
					(unit 1)
				)
			)
		)
	)
	(symbol
		(lib_id "antmicropower:+1V8")
		(at 245.11 243.84 0)
		(unit 1)
		(exclude_from_sim no)
		(in_bom yes)
		(on_board yes)
		(dnp no)
		(property "Reference" "#PWR019"
			(at 260.35 246.38 0)
			(effects
				(font
					(size 1.27 1.27)
					(thickness 0.15)
				)
				(justify left bottom)
				(hide yes)
			)
		)
		(property "Value" "+1V8"
			(at 245.11 240.03 0)
			(effects
				(font
					(size 1.27 1.27)
					(thickness 0.15)
				)
			)
		)
		(property "Footprint" ""
			(at 260.35 251.46 0)
			(effects
				(font
					(size 1.27 1.27)
					(thickness 0.15)
				)
				(justify left bottom)
				(hide yes)
			)
		)
		(property "Datasheet" ""
			(at 260.35 254 0)
			(effects
				(font
					(size 1.27 1.27)
					(thickness 0.15)
				)
				(justify left bottom)
				(hide yes)
			)
		)
		(property "Description" ""
			(at 245.11 243.84 0)
			(effects
				(font
					(size 1.27 1.27)
				)
				(hide yes)
			)
		)
		(property "Author" "Antmicro"
			(at 260.35 248.92 0)
			(effects
				(font
					(size 1.27 1.27)
					(thickness 0.15)
				)
				(justify left bottom)
				(hide yes)
			)
		)
		(property "License" "Apache-2.0"
			(at 260.35 251.46 0)
			(effects
				(font
					(size 1.27 1.27)
					(thickness 0.15)
				)
				(justify left bottom)
				(hide yes)
			)
		)
		(pin "1"
		)
		(instances
			(project "com-express-7-baseboard"
				(path ""
					(reference "#PWR019")
					(unit 1)
				)
			)
		)
	)
	(symbol
		(lib_id "antmicroResistors0402:R_30k_0402")
		(at 368.3 83.82 270)
		(unit 1)
		(exclude_from_sim no)
		(in_bom yes)
		(on_board yes)
		(dnp no)
		(property "Reference" "R117"
			(at 369.57 85.09 90)
			(effects
				(font
					(size 1.27 1.27)
					(thickness 0.15)
				)
				(justify left)
			)
		)
		(property "Value" "R_30k_0402"
			(at 355.6 104.14 0)
			(effects
				(font
					(size 1.27 1.27)
					(thickness 0.15)
				)
				(justify left bottom)
				(hide yes)
			)
		)
		(property "Footprint" "antmicro-footprints:R_0402_1005Metric"
			(at 353.06 104.14 0)
			(effects
				(font
					(size 1.27 1.27)
					(thickness 0.15)
				)
				(justify left bottom)
				(hide yes)
			)
		)
		(property "Datasheet" "https://www.bourns.com/docs/product-datasheets/cr.pdf"
			(at 350.52 104.14 0)
			(effects
				(font
					(size 1.27 1.27)
					(thickness 0.15)
				)
				(justify left bottom)
				(hide yes)
			)
		)
		(property "Description" ""
			(at 368.3 83.82 0)
			(effects
				(font
					(size 1.27 1.27)
				)
				(hide yes)
			)
		)
		(property "MPN" "CR0402-FX-3002GLF"
			(at 347.98 104.14 0)
			(effects
				(font
					(size 1.27 1.27)
					(thickness 0.15)
				)
				(justify left bottom)
				(hide yes)
			)
		)
		(property "Manufacturer" "Bourns"
			(at 345.44 104.14 0)
			(effects
				(font
					(size 1.27 1.27)
					(thickness 0.15)
				)
				(justify left bottom)
				(hide yes)
			)
		)
		(property "License" "Apache-2.0"
			(at 342.9 104.14 0)
			(effects
				(font
					(size 1.27 1.27)
					(thickness 0.15)
				)
				(justify left bottom)
				(hide yes)
			)
		)
		(property "Author" "Antmicro"
			(at 340.36 104.14 0)
			(effects
				(font
					(size 1.27 1.27)
					(thickness 0.15)
				)
				(justify left bottom)
				(hide yes)
			)
		)
		(property "Val" "30k"
			(at 369.57 87.63 90)
			(effects
				(font
					(size 1.27 1.27)
					(thickness 0.15)
				)
				(justify left)
			)
		)
		(property "Tolerance" "1%"
			(at 358.14 104.14 0)
			(effects
				(font
					(size 1.27 1.27)
				)
				(justify left bottom)
				(hide yes)
			)
		)
		(property "Public" "False"
			(at 337.82 104.14 0)
			(effects
				(font
					(size 1.27 1.27)
				)
				(justify left bottom)
				(hide yes)
			)
		)
		(pin "1"
		)
		(pin "2"
		)
		(instances
			(project "com-express-7-baseboard"
				(path ""
					(reference "R117")
					(unit 1)
				)
			)
		)
	)
	(symbol
		(lib_id "antmicroCapacitors0402:C_1u_0402")
		(at 149.86 139.7 90)
		(unit 1)
		(exclude_from_sim no)
		(in_bom yes)
		(on_board yes)
		(dnp no)
		(fields_autoplaced yes)
		(property "Reference" "C50"
			(at 152.4 135.8835 90)
			(effects
				(font
					(size 1.27 1.27)
					(thickness 0.15)
				)
				(justify right)
			)
		)
		(property "Value" "C_1u_0402"
			(at 160.02 119.38 0)
			(effects
				(font
					(size 1.27 1.27)
					(thickness 0.15)
				)
				(justify left bottom)
				(hide yes)
			)
		)
		(property "Footprint" "antmicro-footprints:C_0402_1005Metric"
			(at 162.56 119.38 0)
			(effects
				(font
					(size 1.27 1.27)
					(thickness 0.15)
				)
				(justify left bottom)
				(hide yes)
			)
		)
		(property "Datasheet" "https://product.tdk.com/en/search/capacitor/ceramic/mlcc/info?part_no=C1005X6S1A105K050BC"
			(at 165.1 119.38 0)
			(effects
				(font
					(size 1.27 1.27)
					(thickness 0.15)
				)
				(justify left bottom)
				(hide yes)
			)
		)
		(property "Description" ""
			(at 149.86 139.7 0)
			(effects
				(font
					(size 1.27 1.27)
				)
				(hide yes)
			)
		)
		(property "MPN" "C1005X6S1A105K050BC"
			(at 167.64 119.38 0)
			(effects
				(font
					(size 1.27 1.27)
					(thickness 0.15)
				)
				(justify left bottom)
				(hide yes)
			)
		)
		(property "Manufacturer" "TDK"
			(at 170.18 119.38 0)
			(effects
				(font
					(size 1.27 1.27)
					(thickness 0.15)
				)
				(justify left bottom)
				(hide yes)
			)
		)
		(property "License" "Apache-2.0"
			(at 172.72 119.38 0)
			(effects
				(font
					(size 1.27 1.27)
					(thickness 0.15)
				)
				(justify left bottom)
				(hide yes)
			)
		)
		(property "Author" "Antmicro"
			(at 175.26 119.38 0)
			(effects
				(font
					(size 1.27 1.27)
					(thickness 0.15)
				)
				(justify left bottom)
				(hide yes)
			)
		)
		(property "Val" "1u"
			(at 152.4 138.4235 90)
			(effects
				(font
					(size 1.27 1.27)
					(thickness 0.15)
				)
				(justify right)
			)
		)
		(property "Voltage" ""
			(at 177.8 119.38 0)
			(effects
				(font
					(size 1.27 1.27)
				)
				(justify left bottom)
				(hide yes)
			)
		)
		(property "Dielectric" ""
			(at 180.34 119.38 0)
			(effects
				(font
					(size 1.27 1.27)
				)
				(justify left bottom)
				(hide yes)
			)
		)
		(property "Public" "False"
			(at 182.88 119.38 0)
			(effects
				(font
					(size 1.27 1.27)
				)
				(justify left bottom)
				(hide yes)
			)
		)
		(pin "1"
		)
		(pin "2"
		)
		(instances
			(project "com-express-7-baseboard"
				(path ""
					(reference "C50")
					(unit 1)
				)
			)
		)
	)
	(symbol
		(lib_id "antmicropower:GND")
		(at 69.85 254 0)
		(unit 1)
		(exclude_from_sim no)
		(in_bom yes)
		(on_board yes)
		(dnp no)
		(property "Reference" "#PWR0436"
			(at 78.74 256.54 0)
			(effects
				(font
					(size 1.27 1.27)
					(thickness 0.15)
				)
				(justify left bottom)
				(hide yes)
			)
		)
		(property "Value" "GND"
			(at 69.85 257.81 0)
			(effects
				(font
					(size 1.27 1.27)
					(thickness 0.15)
				)
			)
		)
		(property "Footprint" ""
			(at 78.74 261.62 0)
			(effects
				(font
					(size 1.27 1.27)
					(thickness 0.15)
				)
				(justify left bottom)
				(hide yes)
			)
		)
		(property "Datasheet" ""
			(at 78.74 266.7 0)
			(effects
				(font
					(size 1.27 1.27)
					(thickness 0.15)
				)
				(justify left bottom)
				(hide yes)
			)
		)
		(property "Description" ""
			(at 69.85 254 0)
			(effects
				(font
					(size 1.27 1.27)
				)
				(hide yes)
			)
		)
		(property "Author" "Antmicro"
			(at 78.74 261.62 0)
			(effects
				(font
					(size 1.27 1.27)
					(thickness 0.15)
				)
				(justify left bottom)
				(hide yes)
			)
		)
		(property "License" "Apache-2.0"
			(at 78.74 264.16 0)
			(effects
				(font
					(size 1.27 1.27)
					(thickness 0.15)
				)
				(justify left bottom)
				(hide yes)
			)
		)
		(pin "1"
		)
		(instances
			(project "com-express-7-baseboard"
				(path ""
					(reference "#PWR0436")
					(unit 1)
				)
			)
		)
	)
	(symbol
		(lib_id "antmicroCapacitors0402:C_1u_0402")
		(at 83.82 149.86 90)
		(unit 1)
		(exclude_from_sim no)
		(in_bom yes)
		(on_board yes)
		(dnp no)
		(fields_autoplaced yes)
		(property "Reference" "C45"
			(at 86.36 146.0435 90)
			(effects
				(font
					(size 1.27 1.27)
					(thickness 0.15)
				)
				(justify right)
			)
		)
		(property "Value" "C_1u_0402"
			(at 93.98 129.54 0)
			(effects
				(font
					(size 1.27 1.27)
					(thickness 0.15)
				)
				(justify left bottom)
				(hide yes)
			)
		)
		(property "Footprint" "antmicro-footprints:C_0402_1005Metric"
			(at 96.52 129.54 0)
			(effects
				(font
					(size 1.27 1.27)
					(thickness 0.15)
				)
				(justify left bottom)
				(hide yes)
			)
		)
		(property "Datasheet" "https://product.tdk.com/en/search/capacitor/ceramic/mlcc/info?part_no=C1005X6S1A105K050BC"
			(at 99.06 129.54 0)
			(effects
				(font
					(size 1.27 1.27)
					(thickness 0.15)
				)
				(justify left bottom)
				(hide yes)
			)
		)
		(property "Description" ""
			(at 83.82 149.86 0)
			(effects
				(font
					(size 1.27 1.27)
				)
				(hide yes)
			)
		)
		(property "MPN" "C1005X6S1A105K050BC"
			(at 101.6 129.54 0)
			(effects
				(font
					(size 1.27 1.27)
					(thickness 0.15)
				)
				(justify left bottom)
				(hide yes)
			)
		)
		(property "Manufacturer" "TDK"
			(at 104.14 129.54 0)
			(effects
				(font
					(size 1.27 1.27)
					(thickness 0.15)
				)
				(justify left bottom)
				(hide yes)
			)
		)
		(property "License" "Apache-2.0"
			(at 106.68 129.54 0)
			(effects
				(font
					(size 1.27 1.27)
					(thickness 0.15)
				)
				(justify left bottom)
				(hide yes)
			)
		)
		(property "Author" "Antmicro"
			(at 109.22 129.54 0)
			(effects
				(font
					(size 1.27 1.27)
					(thickness 0.15)
				)
				(justify left bottom)
				(hide yes)
			)
		)
		(property "Val" "1u"
			(at 86.36 148.5835 90)
			(effects
				(font
					(size 1.27 1.27)
					(thickness 0.15)
				)
				(justify right)
			)
		)
		(property "Voltage" ""
			(at 111.76 129.54 0)
			(effects
				(font
					(size 1.27 1.27)
				)
				(justify left bottom)
				(hide yes)
			)
		)
		(property "Dielectric" ""
			(at 114.3 129.54 0)
			(effects
				(font
					(size 1.27 1.27)
				)
				(justify left bottom)
				(hide yes)
			)
		)
		(property "Public" "False"
			(at 116.84 129.54 0)
			(effects
				(font
					(size 1.27 1.27)
				)
				(justify left bottom)
				(hide yes)
			)
		)
		(pin "1"
		)
		(pin "2"
		)
		(instances
			(project "com-express-7-baseboard"
				(path ""
					(reference "C45")
					(unit 1)
				)
			)
		)
	)
	(symbol
		(lib_id "antmicroCapacitors0603:C_22u_16V_0603")
		(at 266.7 138.43 90)
		(unit 1)
		(exclude_from_sim no)
		(in_bom yes)
		(on_board yes)
		(dnp no)
		(fields_autoplaced yes)
		(property "Reference" "C61"
			(at 269.24 133.3435 90)
			(effects
				(font
					(size 1.27 1.27)
					(thickness 0.15)
				)
				(justify right)
			)
		)
		(property "Value" "C_22u_16V_0603"
			(at 276.86 118.11 0)
			(effects
				(font
					(size 1.27 1.27)
					(thickness 0.15)
				)
				(justify left bottom)
				(hide yes)
			)
		)
		(property "Footprint" "antmicro-footprints:C_0603_1608Metric"
			(at 279.4 118.11 0)
			(effects
				(font
					(size 1.27 1.27)
					(thickness 0.15)
				)
				(justify left bottom)
				(hide yes)
			)
		)
		(property "Datasheet" "https://product.samsungsem.com/mlcc/CL10A226MO7JZN.do"
			(at 281.94 118.11 0)
			(effects
				(font
					(size 1.27 1.27)
					(thickness 0.15)
				)
				(justify left bottom)
				(hide yes)
			)
		)
		(property "Description" ""
			(at 266.7 138.43 0)
			(effects
				(font
					(size 1.27 1.27)
				)
				(hide yes)
			)
		)
		(property "MPN" "CL10A226MO7JZNC"
			(at 284.48 118.11 0)
			(effects
				(font
					(size 1.27 1.27)
					(thickness 0.15)
				)
				(justify left bottom)
				(hide yes)
			)
		)
		(property "Manufacturer" "Samsung Electro-Mechanics"
			(at 287.02 118.11 0)
			(effects
				(font
					(size 1.27 1.27)
					(thickness 0.15)
				)
				(justify left bottom)
				(hide yes)
			)
		)
		(property "License" "Apache-2.0"
			(at 289.56 118.11 0)
			(effects
				(font
					(size 1.27 1.27)
					(thickness 0.15)
				)
				(justify left bottom)
				(hide yes)
			)
		)
		(property "Author" "Antmicro"
			(at 292.1 118.11 0)
			(effects
				(font
					(size 1.27 1.27)
					(thickness 0.15)
				)
				(justify left bottom)
				(hide yes)
			)
		)
		(property "Val" "22u"
			(at 269.24 135.8835 90)
			(effects
				(font
					(size 1.27 1.27)
					(thickness 0.15)
				)
				(justify right)
			)
		)
		(property "Voltage" "16V"
			(at 269.24 138.4235 90)
			(effects
				(font
					(size 1.27 1.27)
				)
				(justify right)
				(hide yes)
			)
		)
		(property "Dielectric" ""
			(at 297.18 118.11 0)
			(effects
				(font
					(size 1.27 1.27)
				)
				(justify left bottom)
				(hide yes)
			)
		)
		(property "Public" "False"
			(at 299.72 118.11 0)
			(effects
				(font
					(size 1.27 1.27)
				)
				(justify left bottom)
				(hide yes)
			)
		)
		(pin "2"
		)
		(pin "1"
		)
		(instances
			(project "com-express-7-baseboard"
				(path ""
					(reference "C61")
					(unit 1)
				)
			)
		)
	)
	(symbol
		(lib_id "antmicropower:PWR_FLAG")
		(at 199.39 129.54 270)
		(unit 1)
		(exclude_from_sim no)
		(in_bom yes)
		(on_board yes)
		(dnp no)
		(fields_autoplaced yes)
		(property "Reference" "#FLG010"
			(at 201.295 129.54 0)
			(effects
				(font
					(size 1.27 1.27)
				)
				(hide yes)
			)
		)
		(property "Value" "PWR_FLAG"
			(at 203.2 129.5399 90)
			(effects
				(font
					(size 1.27 1.27)
				)
				(justify left)
			)
		)
		(property "Footprint" ""
			(at 199.39 129.54 0)
			(effects
				(font
					(size 1.27 1.27)
				)
				(hide yes)
			)
		)
		(property "Datasheet" ""
			(at 199.39 129.54 0)
			(effects
				(font
					(size 1.27 1.27)
				)
				(hide yes)
			)
		)
		(property "Description" ""
			(at 199.39 129.54 0)
			(effects
				(font
					(size 1.27 1.27)
				)
				(hide yes)
			)
		)
		(pin "1"
		)
		(instances
			(project "com-express-7-baseboard"
				(path ""
					(reference "#FLG010")
					(unit 1)
				)
			)
		)
	)
	(symbol
		(lib_id "antmicropower:GND")
		(at 48.26 231.14 0)
		(mirror y)
		(unit 1)
		(exclude_from_sim no)
		(in_bom yes)
		(on_board yes)
		(dnp no)
		(property "Reference" "#PWR0447"
			(at 39.37 233.68 0)
			(effects
				(font
					(size 1.27 1.27)
					(thickness 0.15)
				)
				(justify left bottom)
				(hide yes)
			)
		)
		(property "Value" "GND"
			(at 48.26 234.95 0)
			(effects
				(font
					(size 1.27 1.27)
					(thickness 0.15)
				)
			)
		)
		(property "Footprint" ""
			(at 39.37 238.76 0)
			(effects
				(font
					(size 1.27 1.27)
					(thickness 0.15)
				)
				(justify left bottom)
				(hide yes)
			)
		)
		(property "Datasheet" ""
			(at 39.37 243.84 0)
			(effects
				(font
					(size 1.27 1.27)
					(thickness 0.15)
				)
				(justify left bottom)
				(hide yes)
			)
		)
		(property "Description" ""
			(at 48.26 231.14 0)
			(effects
				(font
					(size 1.27 1.27)
				)
				(hide yes)
			)
		)
		(property "Author" "Antmicro"
			(at 39.37 238.76 0)
			(effects
				(font
					(size 1.27 1.27)
					(thickness 0.15)
				)
				(justify left bottom)
				(hide yes)
			)
		)
		(property "License" "Apache-2.0"
			(at 39.37 241.3 0)
			(effects
				(font
					(size 1.27 1.27)
					(thickness 0.15)
				)
				(justify left bottom)
				(hide yes)
			)
		)
		(pin "1"
		)
		(instances
			(project "com-express-7-baseboard"
				(path ""
					(reference "#PWR0447")
					(unit 1)
				)
			)
		)
	)
	(symbol
		(lib_id "antmicroCapacitors0603:C_22u_16V_0603")
		(at 228.6 59.69 90)
		(unit 1)
		(exclude_from_sim no)
		(in_bom yes)
		(on_board yes)
		(dnp no)
		(fields_autoplaced yes)
		(property "Reference" "C58"
			(at 231.14 54.6035 90)
			(effects
				(font
					(size 1.27 1.27)
					(thickness 0.15)
				)
				(justify right)
			)
		)
		(property "Value" "C_22u_16V_0603"
			(at 238.76 39.37 0)
			(effects
				(font
					(size 1.27 1.27)
					(thickness 0.15)
				)
				(justify left bottom)
				(hide yes)
			)
		)
		(property "Footprint" "antmicro-footprints:C_0603_1608Metric"
			(at 241.3 39.37 0)
			(effects
				(font
					(size 1.27 1.27)
					(thickness 0.15)
				)
				(justify left bottom)
				(hide yes)
			)
		)
		(property "Datasheet" "https://product.samsungsem.com/mlcc/CL10A226MO7JZN.do"
			(at 243.84 39.37 0)
			(effects
				(font
					(size 1.27 1.27)
					(thickness 0.15)
				)
				(justify left bottom)
				(hide yes)
			)
		)
		(property "Description" ""
			(at 228.6 59.69 0)
			(effects
				(font
					(size 1.27 1.27)
				)
				(hide yes)
			)
		)
		(property "MPN" "CL10A226MO7JZNC"
			(at 246.38 39.37 0)
			(effects
				(font
					(size 1.27 1.27)
					(thickness 0.15)
				)
				(justify left bottom)
				(hide yes)
			)
		)
		(property "Manufacturer" "Samsung Electro-Mechanics"
			(at 248.92 39.37 0)
			(effects
				(font
					(size 1.27 1.27)
					(thickness 0.15)
				)
				(justify left bottom)
				(hide yes)
			)
		)
		(property "License" "Apache-2.0"
			(at 251.46 39.37 0)
			(effects
				(font
					(size 1.27 1.27)
					(thickness 0.15)
				)
				(justify left bottom)
				(hide yes)
			)
		)
		(property "Author" "Antmicro"
			(at 254 39.37 0)
			(effects
				(font
					(size 1.27 1.27)
					(thickness 0.15)
				)
				(justify left bottom)
				(hide yes)
			)
		)
		(property "Val" "22u"
			(at 231.14 57.1435 90)
			(effects
				(font
					(size 1.27 1.27)
					(thickness 0.15)
				)
				(justify right)
			)
		)
		(property "Voltage" "16V"
			(at 231.14 59.6835 90)
			(effects
				(font
					(size 1.27 1.27)
				)
				(justify right)
				(hide yes)
			)
		)
		(property "Dielectric" ""
			(at 259.08 39.37 0)
			(effects
				(font
					(size 1.27 1.27)
				)
				(justify left bottom)
				(hide yes)
			)
		)
		(property "Public" "False"
			(at 261.62 39.37 0)
			(effects
				(font
					(size 1.27 1.27)
				)
				(justify left bottom)
				(hide yes)
			)
		)
		(pin "2"
		)
		(pin "1"
		)
		(instances
			(project "com-express-7-baseboard"
				(path ""
					(reference "C58")
					(unit 1)
				)
			)
		)
	)
	(symbol
		(lib_id "antmicropower:+3V3_AON")
		(at 165.1 163.83 0)
		(unit 1)
		(exclude_from_sim no)
		(in_bom yes)
		(on_board yes)
		(dnp no)
		(property "Reference" "#PWR0439"
			(at 165.1 167.64 0)
			(effects
				(font
					(size 1.27 1.27)
				)
				(hide yes)
			)
		)
		(property "Value" "+3V3_AON"
			(at 165.1 160.02 0)
			(effects
				(font
					(size 1.27 1.27)
				)
			)
		)
		(property "Footprint" ""
			(at 165.1 163.83 0)
			(effects
				(font
					(size 1.27 1.27)
				)
				(hide yes)
			)
		)
		(property "Datasheet" ""
			(at 165.1 163.83 0)
			(effects
				(font
					(size 1.27 1.27)
				)
				(hide yes)
			)
		)
		(property "Description" ""
			(at 165.1 163.83 0)
			(effects
				(font
					(size 1.27 1.27)
				)
				(hide yes)
			)
		)
		(pin "1"
		)
		(instances
			(project "com-express-7-baseboard"
				(path ""
					(reference "#PWR0439")
					(unit 1)
				)
			)
		)
	)
	(symbol
		(lib_id "antmicroResistors0402:R_470R_0402")
		(at 254 222.25 90)
		(unit 1)
		(exclude_from_sim no)
		(in_bom yes)
		(on_board yes)
		(dnp no)
		(property "Reference" "R327"
			(at 255.27 218.44 90)
			(effects
				(font
					(size 1.27 1.27)
					(thickness 0.15)
				)
				(justify right)
			)
		)
		(property "Value" "R_470R_0402"
			(at 266.7 201.93 0)
			(effects
				(font
					(size 1.27 1.27)
					(thickness 0.15)
				)
				(justify left bottom)
				(hide yes)
			)
		)
		(property "Footprint" "antmicro-footprints:R_0402_1005Metric"
			(at 269.24 201.93 0)
			(effects
				(font
					(size 1.27 1.27)
					(thickness 0.15)
				)
				(justify left bottom)
				(hide yes)
			)
		)
		(property "Datasheet" "https://www.bourns.com/docs/product-datasheets/cr.pdf"
			(at 271.78 201.93 0)
			(effects
				(font
					(size 1.27 1.27)
					(thickness 0.15)
				)
				(justify left bottom)
				(hide yes)
			)
		)
		(property "Description" ""
			(at 254 222.25 0)
			(effects
				(font
					(size 1.27 1.27)
				)
				(hide yes)
			)
		)
		(property "MPN" "CR0402-FX-4700GLF"
			(at 274.32 201.93 0)
			(effects
				(font
					(size 1.27 1.27)
					(thickness 0.15)
				)
				(justify left bottom)
				(hide yes)
			)
		)
		(property "Manufacturer" "Bourns"
			(at 276.86 201.93 0)
			(effects
				(font
					(size 1.27 1.27)
					(thickness 0.15)
				)
				(justify left bottom)
				(hide yes)
			)
		)
		(property "License" "Apache-2.0"
			(at 279.4 201.93 0)
			(effects
				(font
					(size 1.27 1.27)
					(thickness 0.15)
				)
				(justify left bottom)
				(hide yes)
			)
		)
		(property "Author" "Antmicro"
			(at 281.94 201.93 0)
			(effects
				(font
					(size 1.27 1.27)
					(thickness 0.15)
				)
				(justify left bottom)
				(hide yes)
			)
		)
		(property "Val" "470R"
			(at 255.27 220.98 90)
			(effects
				(font
					(size 1.27 1.27)
					(thickness 0.15)
				)
				(justify right)
			)
		)
		(property "Tolerance" "1%"
			(at 264.16 201.93 0)
			(effects
				(font
					(size 1.27 1.27)
				)
				(justify left bottom)
				(hide yes)
			)
		)
		(pin "1"
		)
		(pin "2"
		)
		(instances
			(project "com-express-7-baseboard"
				(path ""
					(reference "R327")
					(unit 1)
				)
			)
		)
	)
	(symbol
		(lib_id "antmicroResistorsmisc:R_0R001_0805")
		(at 167.64 49.53 0)
		(unit 1)
		(exclude_from_sim no)
		(in_bom yes)
		(on_board yes)
		(dnp no)
		(property "Reference" "R103"
			(at 170.18 44.45 0)
			(effects
				(font
					(size 1.27 1.27)
					(thickness 0.15)
				)
			)
		)
		(property "Value" "R_0R001_0805"
			(at 187.96 62.23 0)
			(effects
				(font
					(size 1.27 1.27)
					(thickness 0.15)
				)
				(justify left bottom)
				(hide yes)
			)
		)
		(property "Footprint" "antmicro-footprints:R_0805_2012Metric"
			(at 187.96 64.77 0)
			(effects
				(font
					(size 1.27 1.27)
					(thickness 0.15)
				)
				(justify left bottom)
				(hide yes)
			)
		)
		(property "Datasheet" "https://www.eaton.com/content/dam/eaton/products/electronic-components/resources/data-sheet/eaton-msma-automotive-smd-current-sense-resistor-metal-strip-data-sheet-elx1179.pdf"
			(at 187.96 67.31 0)
			(effects
				(font
					(size 1.27 1.27)
					(thickness 0.15)
				)
				(justify left bottom)
				(hide yes)
			)
		)
		(property "Description" ""
			(at 167.64 49.53 0)
			(effects
				(font
					(size 1.27 1.27)
				)
				(hide yes)
			)
		)
		(property "MPN" "MSMA0805R0010FSM"
			(at 187.96 69.85 0)
			(effects
				(font
					(size 1.27 1.27)
					(thickness 0.15)
				)
				(justify left bottom)
				(hide yes)
			)
		)
		(property "Manufacturer" "Eaton"
			(at 187.96 72.39 0)
			(effects
				(font
					(size 1.27 1.27)
					(thickness 0.15)
				)
				(justify left bottom)
				(hide yes)
			)
		)
		(property "License" "Apache-2.0"
			(at 187.96 74.93 0)
			(effects
				(font
					(size 1.27 1.27)
					(thickness 0.15)
				)
				(justify left bottom)
				(hide yes)
			)
		)
		(property "Author" "Antmicro"
			(at 187.96 77.47 0)
			(effects
				(font
					(size 1.27 1.27)
					(thickness 0.15)
				)
				(justify left bottom)
				(hide yes)
			)
		)
		(property "Val" "0R001"
			(at 170.18 46.99 0)
			(effects
				(font
					(size 1.27 1.27)
					(thickness 0.15)
				)
			)
		)
		(property "Tolerance" "1%"
			(at 187.96 59.69 0)
			(effects
				(font
					(size 1.27 1.27)
				)
				(justify left bottom)
				(hide yes)
			)
		)
		(property "Public" "False"
			(at 187.96 80.01 0)
			(effects
				(font
					(size 1.27 1.27)
				)
				(justify left bottom)
				(hide yes)
			)
		)
		(pin "2"
		)
		(pin "1"
		)
		(instances
			(project "com-express-7-baseboard"
				(path ""
					(reference "R103")
					(unit 1)
				)
			)
		)
	)
	(symbol
		(lib_id "antmicroFixedInductors:L_1u8_6.8A_WE-MAPI-4020")
		(at 280.67 55.88 0)
		(unit 1)
		(exclude_from_sim no)
		(in_bom yes)
		(on_board yes)
		(dnp no)
		(fields_autoplaced yes)
		(property "Reference" "L3"
			(at 283.21 50.8 0)
			(effects
				(font
					(size 1.27 1.27)
					(thickness 0.15)
				)
			)
		)
		(property "Value" "L_1u8_6.8A_WE-MAPI-4020"
			(at 294.64 58.42 0)
			(effects
				(font
					(size 1.27 1.27)
					(thickness 0.15)
				)
				(justify left bottom)
				(hide yes)
			)
		)
		(property "Footprint" "antmicro-footprints:L_WE-MAPI-4020"
			(at 294.64 63.5 0)
			(effects
				(font
					(size 1.27 1.27)
					(thickness 0.15)
				)
				(justify left bottom)
				(hide yes)
			)
		)
		(property "Datasheet" "https://www.we-online.com/components/products/datasheet/74438356018.pdf"
			(at 294.64 66.04 0)
			(effects
				(font
					(size 1.27 1.27)
					(thickness 0.15)
				)
				(justify left bottom)
				(hide yes)
			)
		)
		(property "Description" ""
			(at 280.67 55.88 0)
			(effects
				(font
					(size 1.27 1.27)
				)
				(hide yes)
			)
		)
		(property "Val" "1u8/6.8A"
			(at 283.21 53.34 0)
			(effects
				(font
					(size 1.27 1.27)
					(thickness 0.15)
				)
			)
		)
		(property "Manufacturer" "Würth Elektronik"
			(at 294.64 68.58 0)
			(effects
				(font
					(size 1.27 1.27)
					(thickness 0.15)
				)
				(justify left bottom)
				(hide yes)
			)
		)
		(property "MPN" "74438356018"
			(at 294.64 71.12 0)
			(effects
				(font
					(size 1.27 1.27)
					(thickness 0.15)
				)
				(justify left bottom)
				(hide yes)
			)
		)
		(property "ISat" "6.5 A"
			(at 294.64 72.39 0)
			(effects
				(font
					(size 1.27 1.27)
				)
				(justify left)
				(hide yes)
			)
		)
		(property "IMax" "6.8 A"
			(at 294.64 76.2 0)
			(effects
				(font
					(size 1.27 1.27)
					(thickness 0.15)
				)
				(justify left bottom)
				(hide yes)
			)
		)
		(property "Size" "4.1x4.1mm"
			(at 294.64 78.74 0)
			(effects
				(font
					(size 1.27 1.27)
					(thickness 0.15)
				)
				(justify left bottom)
				(hide yes)
			)
		)
		(property "Author" "Antmicro"
			(at 294.64 81.28 0)
			(effects
				(font
					(size 1.27 1.27)
					(thickness 0.15)
				)
				(justify left bottom)
				(hide yes)
			)
		)
		(property "License" "Apache-2.0"
			(at 294.64 83.82 0)
			(effects
				(font
					(size 1.27 1.27)
					(thickness 0.15)
				)
				(justify left bottom)
				(hide yes)
			)
		)
		(property "Public" "False"
			(at 294.64 86.36 0)
			(effects
				(font
					(size 1.27 1.27)
				)
				(justify left bottom)
				(hide yes)
			)
		)
		(pin "1"
		)
		(pin "2"
		)
		(instances
			(project "com-express-7-baseboard"
				(path ""
					(reference "L3")
					(unit 1)
				)
			)
		)
	)
	(symbol
		(lib_id "antmicroWire2BoardConnectors:Molex_Nano-Fit_1x2_105309-1202")
		(at 33.02 223.52 0)
		(mirror y)
		(unit 1)
		(exclude_from_sim no)
		(in_bom yes)
		(on_board yes)
		(dnp no)
		(property "Reference" "J6"
			(at 28.575 216.535 0)
			(effects
				(font
					(size 1.27 1.27)
					(thickness 0.15)
				)
			)
		)
		(property "Value" "Molex_Nano-Fit_1x2_105309-1202"
			(at 12.7 231.14 0)
			(effects
				(font
					(size 1.27 1.27)
					(thickness 0.15)
				)
				(justify left bottom)
				(hide yes)
			)
		)
		(property "Footprint" "antmicro-footprints:Conn_Molex_Nano-Fit_1x2_105309-1202"
			(at 12.7 233.68 0)
			(effects
				(font
					(size 1.27 1.27)
					(thickness 0.15)
				)
				(justify left bottom)
				(hide yes)
			)
		)
		(property "Datasheet" "https://tools.molex.com/pdm_docs/sd/1053091202_sd.pdf"
			(at 12.7 236.22 0)
			(effects
				(font
					(size 1.27 1.27)
					(thickness 0.15)
				)
				(justify left bottom)
				(hide yes)
			)
		)
		(property "Description" "Pin Header, Power, 2.5 mm, 1 Rows, 2 Contacts, Through Hole Straight, Nano-Fit"
			(at 33.02 223.52 0)
			(effects
				(font
					(size 1.27 1.27)
				)
				(hide yes)
			)
		)
		(property "Manufacturer" "Molex"
			(at 12.7 238.76 0)
			(effects
				(font
					(size 1.27 1.27)
					(thickness 0.15)
				)
				(justify left bottom)
				(hide yes)
			)
		)
		(property "MPN" "105309-1202"
			(at 27.94 219.075 0)
			(effects
				(font
					(size 1.27 1.27)
					(thickness 0.15)
				)
			)
		)
		(property "Author" "Antmicro"
			(at 12.7 241.3 0)
			(effects
				(font
					(size 1.27 1.27)
					(thickness 0.15)
				)
				(justify left bottom)
				(hide yes)
			)
		)
		(property "License" "Apache-2.0"
			(at 12.7 243.84 0)
			(effects
				(font
					(size 1.27 1.27)
					(thickness 0.15)
				)
				(justify left bottom)
				(hide yes)
			)
		)
		(pin "2"
		)
		(pin "1"
		)
		(instances
			(project ""
				(path ""
					(reference "J6")
					(unit 1)
				)
			)
		)
	)
	(symbol
		(lib_id "antmicroLEDIndicationDiscrete:LED_G_0603_LTST-C190GKT")
		(at 227.33 214.63 270)
		(mirror x)
		(unit 1)
		(exclude_from_sim no)
		(in_bom yes)
		(on_board yes)
		(dnp no)
		(property "Reference" "D31"
			(at 227.965 210.185 90)
			(effects
				(font
					(size 1.27 1.27)
				)
				(justify left)
			)
		)
		(property "Value" "LED_G_0603_LTST-C190GKT"
			(at 219.71 191.77 0)
			(effects
				(font
					(size 1.27 1.27)
					(thickness 0.15)
				)
				(justify left bottom)
				(hide yes)
			)
		)
		(property "Footprint" "antmicro-footprints:LED_0603_1608Metric_G"
			(at 217.17 191.77 0)
			(effects
				(font
					(size 1.27 1.27)
					(thickness 0.15)
				)
				(justify left bottom)
				(hide yes)
			)
		)
		(property "Datasheet" "https://media.digikey.com/pdf/Data%20Sheets/Lite-On%20PDFs/LTST-C190GKT.pdf"
			(at 214.63 191.77 0)
			(effects
				(font
					(size 1.27 1.27)
					(thickness 0.15)
				)
				(justify left bottom)
				(hide yes)
			)
		)
		(property "Description" ""
			(at 227.33 214.63 0)
			(effects
				(font
					(size 1.27 1.27)
				)
				(hide yes)
			)
		)
		(property "MPN" "LTST-C190GKT"
			(at 231.14 209.5501 90)
			(effects
				(font
					(size 1.27 1.27)
					(thickness 0.15)
				)
				(justify left)
				(hide yes)
			)
		)
		(property "Manufacturer" "Lite-On"
			(at 209.55 191.77 0)
			(effects
				(font
					(size 1.27 1.27)
					(thickness 0.15)
				)
				(justify left bottom)
				(hide yes)
			)
		)
		(property "Author" "Antmicro"
			(at 207.01 191.77 0)
			(effects
				(font
					(size 1.27 1.27)
					(thickness 0.15)
				)
				(justify left bottom)
				(hide yes)
			)
		)
		(property "License" "Apache-2.0"
			(at 204.47 191.77 0)
			(effects
				(font
					(size 1.27 1.27)
					(thickness 0.15)
				)
				(justify left bottom)
				(hide yes)
			)
		)
		(property "Public" "False"
			(at 209.55 194.31 0)
			(effects
				(font
					(size 1.27 1.27)
				)
				(justify left bottom)
				(hide yes)
			)
		)
		(property "Color" "Green"
			(at 227.965 214.63 90)
			(effects
				(font
					(size 1.27 1.27)
				)
				(justify left)
			)
		)
		(pin "1"
		)
		(pin "2"
		)
		(instances
			(project "com-express-7-baseboard"
				(path ""
					(reference "D31")
					(unit 1)
				)
			)
		)
	)
	(symbol
		(lib_id "antmicroLEDIndicationDiscrete:LED_G_0603_LTST-C190GKT")
		(at 227.33 261.62 270)
		(mirror x)
		(unit 1)
		(exclude_from_sim no)
		(in_bom yes)
		(on_board yes)
		(dnp no)
		(property "Reference" "D30"
			(at 227.965 257.175 90)
			(effects
				(font
					(size 1.27 1.27)
				)
				(justify left)
			)
		)
		(property "Value" "LED_G_0603_LTST-C190GKT"
			(at 219.71 238.76 0)
			(effects
				(font
					(size 1.27 1.27)
					(thickness 0.15)
				)
				(justify left bottom)
				(hide yes)
			)
		)
		(property "Footprint" "antmicro-footprints:LED_0603_1608Metric_G"
			(at 217.17 238.76 0)
			(effects
				(font
					(size 1.27 1.27)
					(thickness 0.15)
				)
				(justify left bottom)
				(hide yes)
			)
		)
		(property "Datasheet" "https://media.digikey.com/pdf/Data%20Sheets/Lite-On%20PDFs/LTST-C190GKT.pdf"
			(at 214.63 238.76 0)
			(effects
				(font
					(size 1.27 1.27)
					(thickness 0.15)
				)
				(justify left bottom)
				(hide yes)
			)
		)
		(property "Description" ""
			(at 227.33 261.62 0)
			(effects
				(font
					(size 1.27 1.27)
				)
				(hide yes)
			)
		)
		(property "MPN" "LTST-C190GKT"
			(at 231.14 256.5401 90)
			(effects
				(font
					(size 1.27 1.27)
					(thickness 0.15)
				)
				(justify left)
				(hide yes)
			)
		)
		(property "Manufacturer" "Lite-On"
			(at 209.55 238.76 0)
			(effects
				(font
					(size 1.27 1.27)
					(thickness 0.15)
				)
				(justify left bottom)
				(hide yes)
			)
		)
		(property "Author" "Antmicro"
			(at 207.01 238.76 0)
			(effects
				(font
					(size 1.27 1.27)
					(thickness 0.15)
				)
				(justify left bottom)
				(hide yes)
			)
		)
		(property "License" "Apache-2.0"
			(at 204.47 238.76 0)
			(effects
				(font
					(size 1.27 1.27)
					(thickness 0.15)
				)
				(justify left bottom)
				(hide yes)
			)
		)
		(property "Public" "False"
			(at 209.55 241.3 0)
			(effects
				(font
					(size 1.27 1.27)
				)
				(justify left bottom)
				(hide yes)
			)
		)
		(property "Color" "Green"
			(at 227.965 261.62 90)
			(effects
				(font
					(size 1.27 1.27)
				)
				(justify left)
			)
		)
		(pin "1"
		)
		(pin "2"
		)
		(instances
			(project "com-express-7-baseboard"
				(path ""
					(reference "D30")
					(unit 1)
				)
			)
		)
	)
	(symbol
		(lib_id "antmicroResistors0402:R_10k_0402")
		(at 248.92 67.31 90)
		(unit 1)
		(exclude_from_sim no)
		(in_bom yes)
		(on_board yes)
		(dnp no)
		(fields_autoplaced yes)
		(property "Reference" "R108"
			(at 251.46 63.4999 90)
			(effects
				(font
					(size 1.27 1.27)
					(thickness 0.15)
				)
				(justify right)
			)
		)
		(property "Value" "R_10k_0402"
			(at 261.62 46.99 0)
			(effects
				(font
					(size 1.27 1.27)
					(thickness 0.15)
				)
				(justify left bottom)
				(hide yes)
			)
		)
		(property "Footprint" "antmicro-footprints:R_0402_1005Metric"
			(at 264.16 46.99 0)
			(effects
				(font
					(size 1.27 1.27)
					(thickness 0.15)
				)
				(justify left bottom)
				(hide yes)
			)
		)
		(property "Datasheet" "https://www.bourns.com/docs/product-datasheets/cr.pdf"
			(at 266.7 46.99 0)
			(effects
				(font
					(size 1.27 1.27)
					(thickness 0.15)
				)
				(justify left bottom)
				(hide yes)
			)
		)
		(property "Description" ""
			(at 248.92 67.31 0)
			(effects
				(font
					(size 1.27 1.27)
				)
				(hide yes)
			)
		)
		(property "MPN" "CR0402-FX-1002GLF"
			(at 269.24 46.99 0)
			(effects
				(font
					(size 1.27 1.27)
					(thickness 0.15)
				)
				(justify left bottom)
				(hide yes)
			)
		)
		(property "Manufacturer" "Bourns"
			(at 271.78 46.99 0)
			(effects
				(font
					(size 1.27 1.27)
					(thickness 0.15)
				)
				(justify left bottom)
				(hide yes)
			)
		)
		(property "License" "Apache-2.0"
			(at 274.32 46.99 0)
			(effects
				(font
					(size 1.27 1.27)
					(thickness 0.15)
				)
				(justify left bottom)
				(hide yes)
			)
		)
		(property "Author" "Antmicro"
			(at 276.86 46.99 0)
			(effects
				(font
					(size 1.27 1.27)
					(thickness 0.15)
				)
				(justify left bottom)
				(hide yes)
			)
		)
		(property "Val" "10k"
			(at 251.46 66.0399 90)
			(effects
				(font
					(size 1.27 1.27)
					(thickness 0.15)
				)
				(justify right)
			)
		)
		(property "Tolerance" "1%"
			(at 259.08 46.99 0)
			(effects
				(font
					(size 1.27 1.27)
				)
				(justify left bottom)
				(hide yes)
			)
		)
		(property "Public" "False"
			(at 279.4 46.99 0)
			(effects
				(font
					(size 1.27 1.27)
				)
				(justify left bottom)
				(hide yes)
			)
		)
		(pin "2"
		)
		(pin "1"
		)
		(instances
			(project "com-express-7-baseboard"
				(path ""
					(reference "R108")
					(unit 1)
				)
			)
		)
	)
	(symbol
		(lib_id "antmicropower:GND")
		(at 309.88 148.59 0)
		(unit 1)
		(exclude_from_sim no)
		(in_bom yes)
		(on_board yes)
		(dnp no)
		(property "Reference" "#PWR0137"
			(at 318.77 151.13 0)
			(effects
				(font
					(size 1.27 1.27)
					(thickness 0.15)
				)
				(justify left bottom)
				(hide yes)
			)
		)
		(property "Value" "GND"
			(at 309.88 152.4 0)
			(effects
				(font
					(size 1.27 1.27)
					(thickness 0.15)
				)
			)
		)
		(property "Footprint" ""
			(at 318.77 156.21 0)
			(effects
				(font
					(size 1.27 1.27)
					(thickness 0.15)
				)
				(justify left bottom)
				(hide yes)
			)
		)
		(property "Datasheet" ""
			(at 318.77 161.29 0)
			(effects
				(font
					(size 1.27 1.27)
					(thickness 0.15)
				)
				(justify left bottom)
				(hide yes)
			)
		)
		(property "Description" ""
			(at 309.88 148.59 0)
			(effects
				(font
					(size 1.27 1.27)
				)
				(hide yes)
			)
		)
		(property "Author" "Antmicro"
			(at 318.77 156.21 0)
			(effects
				(font
					(size 1.27 1.27)
					(thickness 0.15)
				)
				(justify left bottom)
				(hide yes)
			)
		)
		(property "License" "Apache-2.0"
			(at 318.77 158.75 0)
			(effects
				(font
					(size 1.27 1.27)
					(thickness 0.15)
				)
				(justify left bottom)
				(hide yes)
			)
		)
		(pin "1"
		)
		(instances
			(project "com-express-7-baseboard"
				(path ""
					(reference "#PWR0137")
					(unit 1)
				)
			)
		)
	)
	(symbol
		(lib_id "antmicropower:PWR_FLAG")
		(at 393.7 53.34 0)
		(unit 1)
		(exclude_from_sim no)
		(in_bom yes)
		(on_board yes)
		(dnp no)
		(property "Reference" "#FLG013"
			(at 393.7 51.435 0)
			(effects
				(font
					(size 1.27 1.27)
				)
				(hide yes)
			)
		)
		(property "Value" "PWR_FLAG"
			(at 393.7 49.53 0)
			(effects
				(font
					(size 1.27 1.27)
				)
			)
		)
		(property "Footprint" ""
			(at 393.7 53.34 0)
			(effects
				(font
					(size 1.27 1.27)
				)
				(hide yes)
			)
		)
		(property "Datasheet" ""
			(at 393.7 53.34 0)
			(effects
				(font
					(size 1.27 1.27)
				)
				(hide yes)
			)
		)
		(property "Description" ""
			(at 393.7 53.34 0)
			(effects
				(font
					(size 1.27 1.27)
				)
				(hide yes)
			)
		)
		(pin "1"
		)
		(instances
			(project "com-express-7-baseboard"
				(path ""
					(reference "#FLG013")
					(unit 1)
				)
			)
		)
	)
	(symbol
		(lib_id "antmicroResistors0402:R_5k1_0402")
		(at 254 265.43 0)
		(unit 1)
		(exclude_from_sim no)
		(in_bom yes)
		(on_board yes)
		(dnp no)
		(property "Reference" "R329"
			(at 251.46 264.16 0)
			(effects
				(font
					(size 1.27 1.27)
					(thickness 0.15)
				)
			)
		)
		(property "Value" "R_5k1_0402"
			(at 274.32 278.13 0)
			(effects
				(font
					(size 1.27 1.27)
					(thickness 0.15)
				)
				(justify left bottom)
				(hide yes)
			)
		)
		(property "Footprint" "antmicro-footprints:R_0402_1005Metric"
			(at 274.32 280.67 0)
			(effects
				(font
					(size 1.27 1.27)
					(thickness 0.15)
				)
				(justify left bottom)
				(hide yes)
			)
		)
		(property "Datasheet" "https://www.bourns.com/docs/product-datasheets/cr.pdf"
			(at 274.32 283.21 0)
			(effects
				(font
					(size 1.27 1.27)
					(thickness 0.15)
				)
				(justify left bottom)
				(hide yes)
			)
		)
		(property "Description" ""
			(at 254 265.43 0)
			(effects
				(font
					(size 1.27 1.27)
				)
				(hide yes)
			)
		)
		(property "MPN" "CR0402-FX-5101GLF"
			(at 274.32 285.75 0)
			(effects
				(font
					(size 1.27 1.27)
					(thickness 0.15)
				)
				(justify left bottom)
				(hide yes)
			)
		)
		(property "Manufacturer" "Bourns"
			(at 274.32 288.29 0)
			(effects
				(font
					(size 1.27 1.27)
					(thickness 0.15)
				)
				(justify left bottom)
				(hide yes)
			)
		)
		(property "License" "Apache-2.0"
			(at 274.32 290.83 0)
			(effects
				(font
					(size 1.27 1.27)
					(thickness 0.15)
				)
				(justify left bottom)
				(hide yes)
			)
		)
		(property "Author" "Antmicro"
			(at 274.32 293.37 0)
			(effects
				(font
					(size 1.27 1.27)
					(thickness 0.15)
				)
				(justify left bottom)
				(hide yes)
			)
		)
		(property "Val" "5k1"
			(at 260.35 264.16 0)
			(effects
				(font
					(size 1.27 1.27)
					(thickness 0.15)
				)
			)
		)
		(property "Tolerance" "1%"
			(at 274.32 275.59 0)
			(effects
				(font
					(size 1.27 1.27)
				)
				(justify left bottom)
				(hide yes)
			)
		)
		(pin "2"
		)
		(pin "1"
		)
		(instances
			(project "com-express-7-baseboard"
				(path ""
					(reference "R329")
					(unit 1)
				)
			)
		)
	)
	(symbol
		(lib_id "antmicroLEDIndicationDiscrete:LED_G_0603_LTST-C190GKT")
		(at 271.78 243.84 270)
		(mirror x)
		(unit 1)
		(exclude_from_sim no)
		(in_bom yes)
		(on_board yes)
		(dnp no)
		(property "Reference" "D27"
			(at 272.415 239.395 90)
			(effects
				(font
					(size 1.27 1.27)
				)
				(justify left)
			)
		)
		(property "Value" "LED_G_0603_LTST-C190GKT"
			(at 264.16 220.98 0)
			(effects
				(font
					(size 1.27 1.27)
					(thickness 0.15)
				)
				(justify left bottom)
				(hide yes)
			)
		)
		(property "Footprint" "antmicro-footprints:LED_0603_1608Metric_G"
			(at 261.62 220.98 0)
			(effects
				(font
					(size 1.27 1.27)
					(thickness 0.15)
				)
				(justify left bottom)
				(hide yes)
			)
		)
		(property "Datasheet" "https://media.digikey.com/pdf/Data%20Sheets/Lite-On%20PDFs/LTST-C190GKT.pdf"
			(at 259.08 220.98 0)
			(effects
				(font
					(size 1.27 1.27)
					(thickness 0.15)
				)
				(justify left bottom)
				(hide yes)
			)
		)
		(property "Description" ""
			(at 271.78 243.84 0)
			(effects
				(font
					(size 1.27 1.27)
				)
				(hide yes)
			)
		)
		(property "MPN" "LTST-C190GKT"
			(at 275.59 238.7601 90)
			(effects
				(font
					(size 1.27 1.27)
					(thickness 0.15)
				)
				(justify left)
				(hide yes)
			)
		)
		(property "Manufacturer" "Lite-On"
			(at 254 220.98 0)
			(effects
				(font
					(size 1.27 1.27)
					(thickness 0.15)
				)
				(justify left bottom)
				(hide yes)
			)
		)
		(property "Author" "Antmicro"
			(at 251.46 220.98 0)
			(effects
				(font
					(size 1.27 1.27)
					(thickness 0.15)
				)
				(justify left bottom)
				(hide yes)
			)
		)
		(property "License" "Apache-2.0"
			(at 248.92 220.98 0)
			(effects
				(font
					(size 1.27 1.27)
					(thickness 0.15)
				)
				(justify left bottom)
				(hide yes)
			)
		)
		(property "Public" "False"
			(at 254 223.52 0)
			(effects
				(font
					(size 1.27 1.27)
				)
				(justify left bottom)
				(hide yes)
			)
		)
		(property "Color" "Green"
			(at 272.415 243.84 90)
			(effects
				(font
					(size 1.27 1.27)
				)
				(justify left)
			)
		)
		(pin "1"
		)
		(pin "2"
		)
		(instances
			(project "com-express-7-baseboard"
				(path ""
					(reference "D27")
					(unit 1)
				)
			)
		)
	)
	(symbol
		(lib_id "antmicropower:+3V3_AON")
		(at 227.33 243.84 0)
		(unit 1)
		(exclude_from_sim no)
		(in_bom yes)
		(on_board yes)
		(dnp no)
		(property "Reference" "#PWR0462"
			(at 227.33 247.65 0)
			(effects
				(font
					(size 1.27 1.27)
				)
				(hide yes)
			)
		)
		(property "Value" "+3V3_AON"
			(at 227.33 240.03 0)
			(effects
				(font
					(size 1.27 1.27)
				)
			)
		)
		(property "Footprint" ""
			(at 227.33 243.84 0)
			(effects
				(font
					(size 1.27 1.27)
				)
				(hide yes)
			)
		)
		(property "Datasheet" ""
			(at 227.33 243.84 0)
			(effects
				(font
					(size 1.27 1.27)
				)
				(hide yes)
			)
		)
		(property "Description" ""
			(at 227.33 243.84 0)
			(effects
				(font
					(size 1.27 1.27)
				)
				(hide yes)
			)
		)
		(pin "1"
		)
		(instances
			(project "com-express-7-baseboard"
				(path ""
					(reference "#PWR0462")
					(unit 1)
				)
			)
		)
	)
	(symbol
		(lib_id "antmicroResistors0402:R_220R_0402")
		(at 227.33 269.24 90)
		(unit 1)
		(exclude_from_sim no)
		(in_bom yes)
		(on_board yes)
		(dnp no)
		(property "Reference" "R322"
			(at 228.6 265.43 90)
			(effects
				(font
					(size 1.27 1.27)
					(thickness 0.15)
				)
				(justify right)
			)
		)
		(property "Value" "R_220R_0402"
			(at 240.03 248.92 0)
			(effects
				(font
					(size 1.27 1.27)
					(thickness 0.15)
				)
				(justify left bottom)
				(hide yes)
			)
		)
		(property "Footprint" "antmicro-footprints:R_0402_1005Metric"
			(at 242.57 248.92 0)
			(effects
				(font
					(size 1.27 1.27)
					(thickness 0.15)
				)
				(justify left bottom)
				(hide yes)
			)
		)
		(property "Datasheet" "https://www.bourns.com/docs/product-datasheets/cr.pdf"
			(at 245.11 248.92 0)
			(effects
				(font
					(size 1.27 1.27)
					(thickness 0.15)
				)
				(justify left bottom)
				(hide yes)
			)
		)
		(property "Description" ""
			(at 227.33 269.24 0)
			(effects
				(font
					(size 1.27 1.27)
				)
				(hide yes)
			)
		)
		(property "MPN" "CR0402-FX-2200GLF"
			(at 247.65 248.92 0)
			(effects
				(font
					(size 1.27 1.27)
					(thickness 0.15)
				)
				(justify left bottom)
				(hide yes)
			)
		)
		(property "Manufacturer" "Bourns"
			(at 250.19 248.92 0)
			(effects
				(font
					(size 1.27 1.27)
					(thickness 0.15)
				)
				(justify left bottom)
				(hide yes)
			)
		)
		(property "License" "Apache-2.0"
			(at 252.73 248.92 0)
			(effects
				(font
					(size 1.27 1.27)
					(thickness 0.15)
				)
				(justify left bottom)
				(hide yes)
			)
		)
		(property "Author" "Antmicro"
			(at 255.27 248.92 0)
			(effects
				(font
					(size 1.27 1.27)
					(thickness 0.15)
				)
				(justify left bottom)
				(hide yes)
			)
		)
		(property "Val" "220R"
			(at 228.6 267.97 90)
			(effects
				(font
					(size 1.27 1.27)
					(thickness 0.15)
				)
				(justify right)
			)
		)
		(property "Tolerance" "1%"
			(at 237.49 248.92 0)
			(effects
				(font
					(size 1.27 1.27)
				)
				(justify left bottom)
				(hide yes)
			)
		)
		(property "Public" "False"
			(at 257.81 248.92 0)
			(effects
				(font
					(size 1.27 1.27)
				)
				(justify left bottom)
				(hide yes)
			)
		)
		(pin "2"
		)
		(pin "1"
		)
		(instances
			(project "com-express-7-baseboard"
				(path ""
					(reference "R322")
					(unit 1)
				)
			)
		)
	)
	(symbol
		(lib_id "antmicropower:GND")
		(at 139.7 143.51 0)
		(mirror y)
		(unit 1)
		(exclude_from_sim no)
		(in_bom yes)
		(on_board yes)
		(dnp no)
		(property "Reference" "#PWR0111"
			(at 130.81 146.05 0)
			(effects
				(font
					(size 1.27 1.27)
					(thickness 0.15)
				)
				(justify left bottom)
				(hide yes)
			)
		)
		(property "Value" "GND"
			(at 139.7 147.32 0)
			(effects
				(font
					(size 1.27 1.27)
					(thickness 0.15)
				)
			)
		)
		(property "Footprint" ""
			(at 130.81 151.13 0)
			(effects
				(font
					(size 1.27 1.27)
					(thickness 0.15)
				)
				(justify left bottom)
				(hide yes)
			)
		)
		(property "Datasheet" ""
			(at 130.81 156.21 0)
			(effects
				(font
					(size 1.27 1.27)
					(thickness 0.15)
				)
				(justify left bottom)
				(hide yes)
			)
		)
		(property "Description" ""
			(at 139.7 143.51 0)
			(effects
				(font
					(size 1.27 1.27)
				)
				(hide yes)
			)
		)
		(property "Author" "Antmicro"
			(at 130.81 151.13 0)
			(effects
				(font
					(size 1.27 1.27)
					(thickness 0.15)
				)
				(justify left bottom)
				(hide yes)
			)
		)
		(property "License" "Apache-2.0"
			(at 130.81 153.67 0)
			(effects
				(font
					(size 1.27 1.27)
					(thickness 0.15)
				)
				(justify left bottom)
				(hide yes)
			)
		)
		(pin "1"
		)
		(instances
			(project "com-express-7-baseboard"
				(path ""
					(reference "#PWR0111")
					(unit 1)
				)
			)
		)
	)
	(symbol
		(lib_id "antmicroResistors0402:R_470R_0402")
		(at 245.11 222.25 90)
		(unit 1)
		(exclude_from_sim no)
		(in_bom yes)
		(on_board yes)
		(dnp no)
		(property "Reference" "R326"
			(at 246.38 218.44 90)
			(effects
				(font
					(size 1.27 1.27)
					(thickness 0.15)
				)
				(justify right)
			)
		)
		(property "Value" "R_470R_0402"
			(at 257.81 201.93 0)
			(effects
				(font
					(size 1.27 1.27)
					(thickness 0.15)
				)
				(justify left bottom)
				(hide yes)
			)
		)
		(property "Footprint" "antmicro-footprints:R_0402_1005Metric"
			(at 260.35 201.93 0)
			(effects
				(font
					(size 1.27 1.27)
					(thickness 0.15)
				)
				(justify left bottom)
				(hide yes)
			)
		)
		(property "Datasheet" "https://www.bourns.com/docs/product-datasheets/cr.pdf"
			(at 262.89 201.93 0)
			(effects
				(font
					(size 1.27 1.27)
					(thickness 0.15)
				)
				(justify left bottom)
				(hide yes)
			)
		)
		(property "Description" ""
			(at 245.11 222.25 0)
			(effects
				(font
					(size 1.27 1.27)
				)
				(hide yes)
			)
		)
		(property "MPN" "CR0402-FX-4700GLF"
			(at 265.43 201.93 0)
			(effects
				(font
					(size 1.27 1.27)
					(thickness 0.15)
				)
				(justify left bottom)
				(hide yes)
			)
		)
		(property "Manufacturer" "Bourns"
			(at 267.97 201.93 0)
			(effects
				(font
					(size 1.27 1.27)
					(thickness 0.15)
				)
				(justify left bottom)
				(hide yes)
			)
		)
		(property "License" "Apache-2.0"
			(at 270.51 201.93 0)
			(effects
				(font
					(size 1.27 1.27)
					(thickness 0.15)
				)
				(justify left bottom)
				(hide yes)
			)
		)
		(property "Author" "Antmicro"
			(at 273.05 201.93 0)
			(effects
				(font
					(size 1.27 1.27)
					(thickness 0.15)
				)
				(justify left bottom)
				(hide yes)
			)
		)
		(property "Val" "470R"
			(at 246.38 220.98 90)
			(effects
				(font
					(size 1.27 1.27)
					(thickness 0.15)
				)
				(justify right)
			)
		)
		(property "Tolerance" "1%"
			(at 255.27 201.93 0)
			(effects
				(font
					(size 1.27 1.27)
				)
				(justify left bottom)
				(hide yes)
			)
		)
		(pin "1"
		)
		(pin "2"
		)
		(instances
			(project "com-express-7-baseboard"
				(path ""
					(reference "R326")
					(unit 1)
				)
			)
		)
	)
	(symbol
		(lib_id "antmicroResistors0402:R_2k2_0402")
		(at 280.67 251.46 90)
		(unit 1)
		(exclude_from_sim no)
		(in_bom yes)
		(on_board yes)
		(dnp no)
		(property "Reference" "R318"
			(at 281.94 247.65 90)
			(effects
				(font
					(size 1.27 1.27)
					(thickness 0.15)
				)
				(justify right)
			)
		)
		(property "Value" "R_2k2_0402"
			(at 293.37 231.14 0)
			(effects
				(font
					(size 1.27 1.27)
					(thickness 0.15)
				)
				(justify left bottom)
				(hide yes)
			)
		)
		(property "Footprint" "antmicro-footprints:R_0402_1005Metric"
			(at 295.91 231.14 0)
			(effects
				(font
					(size 1.27 1.27)
					(thickness 0.15)
				)
				(justify left bottom)
				(hide yes)
			)
		)
		(property "Datasheet" "https://www.bourns.com/docs/product-datasheets/cr.pdf"
			(at 298.45 231.14 0)
			(effects
				(font
					(size 1.27 1.27)
					(thickness 0.15)
				)
				(justify left bottom)
				(hide yes)
			)
		)
		(property "Description" ""
			(at 280.67 251.46 0)
			(effects
				(font
					(size 1.27 1.27)
				)
				(hide yes)
			)
		)
		(property "MPN" "CR0402-FX-2201GLF"
			(at 300.99 231.14 0)
			(effects
				(font
					(size 1.27 1.27)
					(thickness 0.15)
				)
				(justify left bottom)
				(hide yes)
			)
		)
		(property "Manufacturer" "Bourns"
			(at 303.53 231.14 0)
			(effects
				(font
					(size 1.27 1.27)
					(thickness 0.15)
				)
				(justify left bottom)
				(hide yes)
			)
		)
		(property "License" "Apache-2.0"
			(at 306.07 231.14 0)
			(effects
				(font
					(size 1.27 1.27)
					(thickness 0.15)
				)
				(justify left bottom)
				(hide yes)
			)
		)
		(property "Author" "Antmicro"
			(at 308.61 231.14 0)
			(effects
				(font
					(size 1.27 1.27)
					(thickness 0.15)
				)
				(justify left bottom)
				(hide yes)
			)
		)
		(property "Val" "2k2"
			(at 281.94 250.19 90)
			(effects
				(font
					(size 1.27 1.27)
					(thickness 0.15)
				)
				(justify right)
			)
		)
		(property "Tolerance" "1%"
			(at 290.83 231.14 0)
			(effects
				(font
					(size 1.27 1.27)
				)
				(justify left bottom)
				(hide yes)
			)
		)
		(pin "1"
		)
		(pin "2"
		)
		(instances
			(project "com-express-7-baseboard"
				(path ""
					(reference "R318")
					(unit 1)
				)
			)
		)
	)
	(symbol
		(lib_id "antmicropower:GND")
		(at 320.04 148.59 0)
		(unit 1)
		(exclude_from_sim no)
		(in_bom yes)
		(on_board yes)
		(dnp no)
		(property "Reference" "#PWR0139"
			(at 328.93 151.13 0)
			(effects
				(font
					(size 1.27 1.27)
					(thickness 0.15)
				)
				(justify left bottom)
				(hide yes)
			)
		)
		(property "Value" "GND"
			(at 320.04 152.4 0)
			(effects
				(font
					(size 1.27 1.27)
					(thickness 0.15)
				)
			)
		)
		(property "Footprint" ""
			(at 328.93 156.21 0)
			(effects
				(font
					(size 1.27 1.27)
					(thickness 0.15)
				)
				(justify left bottom)
				(hide yes)
			)
		)
		(property "Datasheet" ""
			(at 328.93 161.29 0)
			(effects
				(font
					(size 1.27 1.27)
					(thickness 0.15)
				)
				(justify left bottom)
				(hide yes)
			)
		)
		(property "Description" ""
			(at 320.04 148.59 0)
			(effects
				(font
					(size 1.27 1.27)
				)
				(hide yes)
			)
		)
		(property "Author" "Antmicro"
			(at 328.93 156.21 0)
			(effects
				(font
					(size 1.27 1.27)
					(thickness 0.15)
				)
				(justify left bottom)
				(hide yes)
			)
		)
		(property "License" "Apache-2.0"
			(at 328.93 158.75 0)
			(effects
				(font
					(size 1.27 1.27)
					(thickness 0.15)
				)
				(justify left bottom)
				(hide yes)
			)
		)
		(pin "1"
		)
		(instances
			(project "com-express-7-baseboard"
				(path ""
					(reference "#PWR0139")
					(unit 1)
				)
			)
		)
	)
	(symbol
		(lib_id "antmicroDiodesRectifiersSingle:BAT54C")
		(at 68.58 139.7 270)
		(unit 1)
		(exclude_from_sim no)
		(in_bom yes)
		(on_board yes)
		(dnp no)
		(fields_autoplaced yes)
		(property "Reference" "D36"
			(at 59.69 144.78 90)
			(effects
				(font
					(size 1.27 1.27)
					(thickness 0.15)
				)
				(justify right)
			)
		)
		(property "Value" "BAT54C"
			(at 59.69 162.56 0)
			(effects
				(font
					(size 1.27 1.27)
					(thickness 0.15)
				)
				(justify left bottom)
				(hide yes)
			)
		)
		(property "Footprint" "antmicro-footprints:SOT-23-3"
			(at 57.15 162.56 0)
			(effects
				(font
					(size 1.27 1.27)
					(thickness 0.15)
				)
				(justify left bottom)
				(hide yes)
			)
		)
		(property "Datasheet" "https://diotec.com/request/datasheet/bat54.pdf"
			(at 54.61 162.56 0)
			(effects
				(font
					(size 1.27 1.27)
					(thickness 0.15)
				)
				(justify left bottom)
				(hide yes)
			)
		)
		(property "Description" ""
			(at 68.58 139.7 0)
			(effects
				(font
					(size 1.27 1.27)
				)
				(hide yes)
			)
		)
		(property "MPN" "BAT54C"
			(at 59.69 147.32 90)
			(effects
				(font
					(size 1.27 1.27)
					(thickness 0.15)
				)
				(justify right)
			)
		)
		(property "Manufacturer" "Diotec Semiconductor"
			(at 52.07 162.56 0)
			(effects
				(font
					(size 1.27 1.27)
					(thickness 0.15)
				)
				(justify left bottom)
				(hide yes)
			)
		)
		(property "Author" "Antmicro"
			(at 49.53 162.56 0)
			(effects
				(font
					(size 1.27 1.27)
					(thickness 0.15)
				)
				(justify left bottom)
				(hide yes)
			)
		)
		(property "License" "Apache-2.0"
			(at 46.99 162.56 0)
			(effects
				(font
					(size 1.27 1.27)
					(thickness 0.15)
				)
				(justify left bottom)
				(hide yes)
			)
		)
		(pin "1"
		)
		(pin "3"
		)
		(pin "2"
		)
		(instances
			(project "com-express-7-baseboard"
				(path ""
					(reference "D36")
					(unit 1)
				)
			)
		)
	)
	(symbol
		(lib_id "antmicroFixedInductors:L_1u8_6.8A_WE-MAPI-4020")
		(at 133.35 49.53 0)
		(unit 1)
		(exclude_from_sim no)
		(in_bom yes)
		(on_board yes)
		(dnp no)
		(fields_autoplaced yes)
		(property "Reference" "L1"
			(at 135.89 44.45 0)
			(effects
				(font
					(size 1.27 1.27)
					(thickness 0.15)
				)
			)
		)
		(property "Value" "L_1u8_6.8A_WE-MAPI-4020"
			(at 147.32 52.07 0)
			(effects
				(font
					(size 1.27 1.27)
					(thickness 0.15)
				)
				(justify left bottom)
				(hide yes)
			)
		)
		(property "Footprint" "antmicro-footprints:L_WE-MAPI-4020"
			(at 147.32 57.15 0)
			(effects
				(font
					(size 1.27 1.27)
					(thickness 0.15)
				)
				(justify left bottom)
				(hide yes)
			)
		)
		(property "Datasheet" "https://www.we-online.com/components/products/datasheet/74438356018.pdf"
			(at 147.32 59.69 0)
			(effects
				(font
					(size 1.27 1.27)
					(thickness 0.15)
				)
				(justify left bottom)
				(hide yes)
			)
		)
		(property "Description" ""
			(at 133.35 49.53 0)
			(effects
				(font
					(size 1.27 1.27)
				)
				(hide yes)
			)
		)
		(property "Val" "1u8/6.8A"
			(at 135.89 46.99 0)
			(effects
				(font
					(size 1.27 1.27)
					(thickness 0.15)
				)
			)
		)
		(property "Manufacturer" "Würth Elektronik"
			(at 147.32 62.23 0)
			(effects
				(font
					(size 1.27 1.27)
					(thickness 0.15)
				)
				(justify left bottom)
				(hide yes)
			)
		)
		(property "MPN" "74438356018"
			(at 147.32 64.77 0)
			(effects
				(font
					(size 1.27 1.27)
					(thickness 0.15)
				)
				(justify left bottom)
				(hide yes)
			)
		)
		(property "ISat" "6.5 A"
			(at 147.32 66.04 0)
			(effects
				(font
					(size 1.27 1.27)
				)
				(justify left)
				(hide yes)
			)
		)
		(property "IMax" "6.8 A"
			(at 147.32 69.85 0)
			(effects
				(font
					(size 1.27 1.27)
					(thickness 0.15)
				)
				(justify left bottom)
				(hide yes)
			)
		)
		(property "Size" "4.1x4.1mm"
			(at 147.32 72.39 0)
			(effects
				(font
					(size 1.27 1.27)
					(thickness 0.15)
				)
				(justify left bottom)
				(hide yes)
			)
		)
		(property "Author" "Antmicro"
			(at 147.32 74.93 0)
			(effects
				(font
					(size 1.27 1.27)
					(thickness 0.15)
				)
				(justify left bottom)
				(hide yes)
			)
		)
		(property "License" "Apache-2.0"
			(at 147.32 77.47 0)
			(effects
				(font
					(size 1.27 1.27)
					(thickness 0.15)
				)
				(justify left bottom)
				(hide yes)
			)
		)
		(property "Public" "False"
			(at 147.32 80.01 0)
			(effects
				(font
					(size 1.27 1.27)
				)
				(justify left bottom)
				(hide yes)
			)
		)
		(pin "1"
		)
		(pin "2"
		)
		(instances
			(project "com-express-7-baseboard"
				(path ""
					(reference "L1")
					(unit 1)
				)
			)
		)
	)
	(symbol
		(lib_id "antmicroLEDIndicationDiscrete:LED_G_0603_LTST-C190GKT")
		(at 236.22 214.63 270)
		(mirror x)
		(unit 1)
		(exclude_from_sim no)
		(in_bom yes)
		(on_board yes)
		(dnp no)
		(property "Reference" "D32"
			(at 236.855 210.185 90)
			(effects
				(font
					(size 1.27 1.27)
				)
				(justify left)
			)
		)
		(property "Value" "LED_G_0603_LTST-C190GKT"
			(at 228.6 191.77 0)
			(effects
				(font
					(size 1.27 1.27)
					(thickness 0.15)
				)
				(justify left bottom)
				(hide yes)
			)
		)
		(property "Footprint" "antmicro-footprints:LED_0603_1608Metric_G"
			(at 226.06 191.77 0)
			(effects
				(font
					(size 1.27 1.27)
					(thickness 0.15)
				)
				(justify left bottom)
				(hide yes)
			)
		)
		(property "Datasheet" "https://media.digikey.com/pdf/Data%20Sheets/Lite-On%20PDFs/LTST-C190GKT.pdf"
			(at 223.52 191.77 0)
			(effects
				(font
					(size 1.27 1.27)
					(thickness 0.15)
				)
				(justify left bottom)
				(hide yes)
			)
		)
		(property "Description" ""
			(at 236.22 214.63 0)
			(effects
				(font
					(size 1.27 1.27)
				)
				(hide yes)
			)
		)
		(property "MPN" "LTST-C190GKT"
			(at 240.03 209.5501 90)
			(effects
				(font
					(size 1.27 1.27)
					(thickness 0.15)
				)
				(justify left)
				(hide yes)
			)
		)
		(property "Manufacturer" "Lite-On"
			(at 218.44 191.77 0)
			(effects
				(font
					(size 1.27 1.27)
					(thickness 0.15)
				)
				(justify left bottom)
				(hide yes)
			)
		)
		(property "Author" "Antmicro"
			(at 215.9 191.77 0)
			(effects
				(font
					(size 1.27 1.27)
					(thickness 0.15)
				)
				(justify left bottom)
				(hide yes)
			)
		)
		(property "License" "Apache-2.0"
			(at 213.36 191.77 0)
			(effects
				(font
					(size 1.27 1.27)
					(thickness 0.15)
				)
				(justify left bottom)
				(hide yes)
			)
		)
		(property "Public" "False"
			(at 218.44 194.31 0)
			(effects
				(font
					(size 1.27 1.27)
				)
				(justify left bottom)
				(hide yes)
			)
		)
		(property "Color" "Green"
			(at 236.855 214.63 90)
			(effects
				(font
					(size 1.27 1.27)
				)
				(justify left)
			)
		)
		(pin "1"
		)
		(pin "2"
		)
		(instances
			(project "com-express-7-baseboard"
				(path ""
					(reference "D32")
					(unit 1)
				)
			)
		)
	)
	(symbol
		(lib_id "antmicroTestPoints:TP_0.75mm_SMD")
		(at 257.81 204.47 0)
		(mirror x)
		(unit 1)
		(exclude_from_sim no)
		(in_bom no)
		(on_board yes)
		(dnp no)
		(property "Reference" "TP103"
			(at 261.62 204.47 0)
			(effects
				(font
					(size 1.27 1.27)
					(thickness 0.15)
				)
				(justify left)
			)
		)
		(property "Value" "TP_0.75mm_SMD"
			(at 268.605 200.66 0)
			(effects
				(font
					(size 1.27 1.27)
					(thickness 0.15)
				)
				(justify left bottom)
				(hide yes)
			)
		)
		(property "Footprint" "antmicro-footprints:TP_SMD_0.75mm"
			(at 268.605 198.12 0)
			(effects
				(font
					(size 1.27 1.27)
					(thickness 0.15)
				)
				(justify left bottom)
				(hide yes)
			)
		)
		(property "Datasheet" ""
			(at 275.59 191.77 0)
			(effects
				(font
					(size 1.27 1.27)
					(thickness 0.15)
				)
				(justify left bottom)
				(hide yes)
			)
		)
		(property "Description" ""
			(at 257.81 204.47 0)
			(effects
				(font
					(size 1.27 1.27)
				)
				(hide yes)
			)
		)
		(property "MPN" ""
			(at 268.605 193.04 0)
			(effects
				(font
					(size 1.27 1.27)
					(thickness 0.15)
				)
				(justify left bottom)
				(hide yes)
			)
		)
		(property "Manufacturer" ""
			(at 268.605 198.12 0)
			(effects
				(font
					(size 1.27 1.27)
					(thickness 0.15)
				)
				(justify left bottom)
				(hide yes)
			)
		)
		(property "Author" "Antmicro"
			(at 268.605 195.58 0)
			(effects
				(font
					(size 1.27 1.27)
					(thickness 0.15)
				)
				(justify left bottom)
				(hide yes)
			)
		)
		(property "License" "Apache-2.0"
			(at 268.605 193.04 0)
			(effects
				(font
					(size 1.27 1.27)
					(thickness 0.15)
				)
				(justify left bottom)
				(hide yes)
			)
		)
		(property "Public" "False"
			(at 267.97 190.5 0)
			(effects
				(font
					(size 1.27 1.27)
				)
				(justify left bottom)
				(hide yes)
			)
		)
		(pin "1"
		)
		(instances
			(project "com-express-7-baseboard"
				(path ""
					(reference "TP103")
					(unit 1)
				)
			)
		)
	)
	(symbol
		(lib_id "antmicropower:+12V_AON")
		(at 257.81 129.54 0)
		(unit 1)
		(exclude_from_sim no)
		(in_bom yes)
		(on_board yes)
		(dnp no)
		(fields_autoplaced yes)
		(property "Reference" "#PWR0130"
			(at 257.81 133.35 0)
			(effects
				(font
					(size 1.27 1.27)
				)
				(hide yes)
			)
		)
		(property "Value" "+12V_AON"
			(at 257.81 124.46 0)
			(effects
				(font
					(size 1.27 1.27)
				)
			)
		)
		(property "Footprint" ""
			(at 257.81 129.54 0)
			(effects
				(font
					(size 1.27 1.27)
				)
				(hide yes)
			)
		)
		(property "Datasheet" ""
			(at 257.81 129.54 0)
			(effects
				(font
					(size 1.27 1.27)
				)
				(hide yes)
			)
		)
		(property "Description" ""
			(at 257.81 129.54 0)
			(effects
				(font
					(size 1.27 1.27)
				)
				(hide yes)
			)
		)
		(pin "1"
		)
		(instances
			(project "com-express-7-baseboard"
				(path ""
					(reference "#PWR0130")
					(unit 1)
				)
			)
		)
	)
	(symbol
		(lib_id "antmicroResistors0402:R_68k_0402")
		(at 90.17 64.77 90)
		(unit 1)
		(exclude_from_sim no)
		(in_bom yes)
		(on_board yes)
		(dnp yes)
		(fields_autoplaced yes)
		(property "Reference" "R88"
			(at 92.71 59.6899 90)
			(effects
				(font
					(size 1.27 1.27)
					(thickness 0.15)
				)
				(justify right)
			)
		)
		(property "Value" "R_68k_0402"
			(at 102.87 44.45 0)
			(effects
				(font
					(size 1.27 1.27)
					(thickness 0.15)
				)
				(justify left bottom)
				(hide yes)
			)
		)
		(property "Footprint" "antmicro-footprints:R_0402_1005Metric"
			(at 105.41 44.45 0)
			(effects
				(font
					(size 1.27 1.27)
					(thickness 0.15)
				)
				(justify left bottom)
				(hide yes)
			)
		)
		(property "Datasheet" "https://www.bourns.com/docs/product-datasheets/cr.pdf"
			(at 107.95 44.45 0)
			(effects
				(font
					(size 1.27 1.27)
					(thickness 0.15)
				)
				(justify left bottom)
				(hide yes)
			)
		)
		(property "Description" ""
			(at 90.17 64.77 0)
			(effects
				(font
					(size 1.27 1.27)
				)
				(hide yes)
			)
		)
		(property "MPN" "CR0402-FX-6802GLF"
			(at 110.49 44.45 0)
			(effects
				(font
					(size 1.27 1.27)
					(thickness 0.15)
				)
				(justify left bottom)
				(hide yes)
			)
		)
		(property "Manufacturer" "Bourns"
			(at 113.03 44.45 0)
			(effects
				(font
					(size 1.27 1.27)
					(thickness 0.15)
				)
				(justify left bottom)
				(hide yes)
			)
		)
		(property "License" "Apache-2.0"
			(at 115.57 44.45 0)
			(effects
				(font
					(size 1.27 1.27)
					(thickness 0.15)
				)
				(justify left bottom)
				(hide yes)
			)
		)
		(property "Author" "Antmicro"
			(at 118.11 44.45 0)
			(effects
				(font
					(size 1.27 1.27)
					(thickness 0.15)
				)
				(justify left bottom)
				(hide yes)
			)
		)
		(property "Val" "68k"
			(at 92.71 62.2299 90)
			(effects
				(font
					(size 1.27 1.27)
					(thickness 0.15)
				)
				(justify right)
			)
		)
		(property "Tolerance" "1%"
			(at 100.33 44.45 0)
			(effects
				(font
					(size 1.27 1.27)
				)
				(justify left bottom)
				(hide yes)
			)
		)
		(property "Public" "False"
			(at 120.65 44.45 0)
			(effects
				(font
					(size 1.27 1.27)
				)
				(justify left bottom)
				(hide yes)
			)
		)
		(pin "1"
		)
		(pin "2"
		)
		(instances
			(project "com-express-7-baseboard"
				(path ""
					(reference "R88")
					(unit 1)
				)
			)
		)
	)
	(symbol
		(lib_id "antmicroCapacitors0402:C_1u_0402")
		(at 320.04 144.78 90)
		(unit 1)
		(exclude_from_sim no)
		(in_bom yes)
		(on_board yes)
		(dnp no)
		(fields_autoplaced yes)
		(property "Reference" "C63"
			(at 322.58 140.9635 90)
			(effects
				(font
					(size 1.27 1.27)
					(thickness 0.15)
				)
				(justify right)
			)
		)
		(property "Value" "C_1u_0402"
			(at 330.2 124.46 0)
			(effects
				(font
					(size 1.27 1.27)
					(thickness 0.15)
				)
				(justify left bottom)
				(hide yes)
			)
		)
		(property "Footprint" "antmicro-footprints:C_0402_1005Metric"
			(at 332.74 124.46 0)
			(effects
				(font
					(size 1.27 1.27)
					(thickness 0.15)
				)
				(justify left bottom)
				(hide yes)
			)
		)
		(property "Datasheet" "https://product.tdk.com/en/search/capacitor/ceramic/mlcc/info?part_no=C1005X6S1A105K050BC"
			(at 335.28 124.46 0)
			(effects
				(font
					(size 1.27 1.27)
					(thickness 0.15)
				)
				(justify left bottom)
				(hide yes)
			)
		)
		(property "Description" ""
			(at 320.04 144.78 0)
			(effects
				(font
					(size 1.27 1.27)
				)
				(hide yes)
			)
		)
		(property "MPN" "C1005X6S1A105K050BC"
			(at 337.82 124.46 0)
			(effects
				(font
					(size 1.27 1.27)
					(thickness 0.15)
				)
				(justify left bottom)
				(hide yes)
			)
		)
		(property "Manufacturer" "TDK"
			(at 340.36 124.46 0)
			(effects
				(font
					(size 1.27 1.27)
					(thickness 0.15)
				)
				(justify left bottom)
				(hide yes)
			)
		)
		(property "License" "Apache-2.0"
			(at 342.9 124.46 0)
			(effects
				(font
					(size 1.27 1.27)
					(thickness 0.15)
				)
				(justify left bottom)
				(hide yes)
			)
		)
		(property "Author" "Antmicro"
			(at 345.44 124.46 0)
			(effects
				(font
					(size 1.27 1.27)
					(thickness 0.15)
				)
				(justify left bottom)
				(hide yes)
			)
		)
		(property "Val" "1u"
			(at 322.58 143.5035 90)
			(effects
				(font
					(size 1.27 1.27)
					(thickness 0.15)
				)
				(justify right)
			)
		)
		(property "Voltage" ""
			(at 347.98 124.46 0)
			(effects
				(font
					(size 1.27 1.27)
				)
				(justify left bottom)
				(hide yes)
			)
		)
		(property "Dielectric" ""
			(at 350.52 124.46 0)
			(effects
				(font
					(size 1.27 1.27)
				)
				(justify left bottom)
				(hide yes)
			)
		)
		(property "Public" "False"
			(at 353.06 124.46 0)
			(effects
				(font
					(size 1.27 1.27)
				)
				(justify left bottom)
				(hide yes)
			)
		)
		(pin "1"
		)
		(pin "2"
		)
		(instances
			(project "com-express-7-baseboard"
				(path ""
					(reference "C63")
					(unit 1)
				)
			)
		)
	)
	(symbol
		(lib_id "antmicropower:+5V")
		(at 254 196.85 0)
		(unit 1)
		(exclude_from_sim no)
		(in_bom yes)
		(on_board yes)
		(dnp no)
		(fields_autoplaced yes)
		(property "Reference" "#PWR0459"
			(at 269.24 199.39 0)
			(effects
				(font
					(size 1.27 1.27)
					(thickness 0.15)
				)
				(justify left bottom)
				(hide yes)
			)
		)
		(property "Value" "+5V"
			(at 254 193.04 0)
			(effects
				(font
					(size 1.27 1.27)
					(thickness 0.15)
				)
			)
		)
		(property "Footprint" ""
			(at 269.24 204.47 0)
			(effects
				(font
					(size 1.27 1.27)
					(thickness 0.15)
				)
				(justify left bottom)
				(hide yes)
			)
		)
		(property "Datasheet" ""
			(at 269.24 207.01 0)
			(effects
				(font
					(size 1.27 1.27)
					(thickness 0.15)
				)
				(justify left bottom)
				(hide yes)
			)
		)
		(property "Description" ""
			(at 254 196.85 0)
			(effects
				(font
					(size 1.27 1.27)
				)
				(hide yes)
			)
		)
		(property "Author" "Antmicro"
			(at 269.24 204.47 0)
			(effects
				(font
					(size 1.27 1.27)
					(thickness 0.15)
				)
				(justify left bottom)
				(hide yes)
			)
		)
		(property "License" "Apache-2.0"
			(at 269.24 207.01 0)
			(effects
				(font
					(size 1.27 1.27)
					(thickness 0.15)
				)
				(justify left bottom)
				(hide yes)
			)
		)
		(pin "1"
		)
		(instances
			(project "com-express-7-baseboard"
				(path ""
					(reference "#PWR0459")
					(unit 1)
				)
			)
		)
	)
	(symbol
		(lib_id "antmicropower:GND")
		(at 311.15 69.85 0)
		(unit 1)
		(exclude_from_sim no)
		(in_bom yes)
		(on_board yes)
		(dnp no)
		(property "Reference" "#PWR0140"
			(at 320.04 72.39 0)
			(effects
				(font
					(size 1.27 1.27)
					(thickness 0.15)
				)
				(justify left bottom)
				(hide yes)
			)
		)
		(property "Value" "GND"
			(at 311.15 73.66 0)
			(effects
				(font
					(size 1.27 1.27)
					(thickness 0.15)
				)
			)
		)
		(property "Footprint" ""
			(at 320.04 77.47 0)
			(effects
				(font
					(size 1.27 1.27)
					(thickness 0.15)
				)
				(justify left bottom)
				(hide yes)
			)
		)
		(property "Datasheet" ""
			(at 320.04 82.55 0)
			(effects
				(font
					(size 1.27 1.27)
					(thickness 0.15)
				)
				(justify left bottom)
				(hide yes)
			)
		)
		(property "Description" ""
			(at 311.15 69.85 0)
			(effects
				(font
					(size 1.27 1.27)
				)
				(hide yes)
			)
		)
		(property "Author" "Antmicro"
			(at 320.04 77.47 0)
			(effects
				(font
					(size 1.27 1.27)
					(thickness 0.15)
				)
				(justify left bottom)
				(hide yes)
			)
		)
		(property "License" "Apache-2.0"
			(at 320.04 80.01 0)
			(effects
				(font
					(size 1.27 1.27)
					(thickness 0.15)
				)
				(justify left bottom)
				(hide yes)
			)
		)
		(pin "1"
		)
		(instances
			(project "com-express-7-baseboard"
				(path ""
					(reference "#PWR0140")
					(unit 1)
				)
			)
		)
	)
	(symbol
		(lib_id "antmicroDCDCConverters:TPS564247DRLR")
		(at 279.4 134.62 0)
		(unit 1)
		(exclude_from_sim no)
		(in_bom yes)
		(on_board yes)
		(dnp no)
		(fields_autoplaced yes)
		(property "Reference" "U22"
			(at 287.02 128.27 0)
			(effects
				(font
					(size 1.27 1.27)
				)
			)
		)
		(property "Value" "TPS564247DRLR"
			(at 279.4 134.62 0)
			(effects
				(font
					(size 1.27 1.27)
				)
				(hide yes)
			)
		)
		(property "Footprint" "antmicro-footprints:SOT-563"
			(at 279.4 134.62 0)
			(effects
				(font
					(size 1.27 1.27)
				)
				(hide yes)
			)
		)
		(property "Datasheet" "https://www.ti.com/lit/ds/symlink/tps564247.pdf?ts=1713526387938&ref_url=https%253A%252F%252Fwww.mouser.pl%252F"
			(at 279.4 134.62 0)
			(effects
				(font
					(size 1.27 1.27)
				)
				(hide yes)
			)
		)
		(property "Description" ""
			(at 279.4 134.62 0)
			(effects
				(font
					(size 1.27 1.27)
				)
				(hide yes)
			)
		)
		(property "MPN" "TPS564247DRLR"
			(at 287.02 130.81 0)
			(effects
				(font
					(size 1.27 1.27)
				)
			)
		)
		(property "Author" "Antmicro"
			(at 309.88 154.94 0)
			(effects
				(font
					(size 1.27 1.27)
					(thickness 0.15)
				)
				(justify left bottom)
				(hide yes)
			)
		)
		(property "License" "Apache-2.0"
			(at 309.88 157.48 0)
			(effects
				(font
					(size 1.27 1.27)
					(thickness 0.15)
				)
				(justify left bottom)
				(hide yes)
			)
		)
		(property "Manufacturer" "Texas Instruments"
			(at 309.88 152.4 0)
			(effects
				(font
					(size 1.27 1.27)
					(thickness 0.15)
				)
				(justify left bottom)
				(hide yes)
			)
		)
		(pin "1"
		)
		(pin "6"
		)
		(pin "2"
		)
		(pin "3"
		)
		(pin "5"
		)
		(pin "4"
		)
		(instances
			(project "com-express-7-baseboard"
				(path ""
					(reference "U22")
					(unit 1)
				)
			)
		)
	)
	(symbol
		(lib_id "antmicroResistors0402:R_100k_0402")
		(at 88.9 252.73 90)
		(unit 1)
		(exclude_from_sim no)
		(in_bom yes)
		(on_board yes)
		(dnp no)
		(property "Reference" "R90"
			(at 87.63 248.92 90)
			(effects
				(font
					(size 1.27 1.27)
					(thickness 0.15)
				)
				(justify left)
			)
		)
		(property "Value" "R_100k_0402"
			(at 101.6 232.41 0)
			(effects
				(font
					(size 1.27 1.27)
					(thickness 0.15)
				)
				(justify left bottom)
				(hide yes)
			)
		)
		(property "Footprint" "antmicro-footprints:R_0402_1005Metric"
			(at 104.14 232.41 0)
			(effects
				(font
					(size 1.27 1.27)
					(thickness 0.15)
				)
				(justify left bottom)
				(hide yes)
			)
		)
		(property "Datasheet" "https://www.bourns.com/docs/product-datasheets/cr.pdf"
			(at 106.68 232.41 0)
			(effects
				(font
					(size 1.27 1.27)
					(thickness 0.15)
				)
				(justify left bottom)
				(hide yes)
			)
		)
		(property "Description" ""
			(at 88.9 252.73 0)
			(effects
				(font
					(size 1.27 1.27)
				)
				(hide yes)
			)
		)
		(property "MPN" "CR0402-FX-1003GLF"
			(at 109.22 232.41 0)
			(effects
				(font
					(size 1.27 1.27)
					(thickness 0.15)
				)
				(justify left bottom)
				(hide yes)
			)
		)
		(property "Manufacturer" "Bourns"
			(at 111.76 232.41 0)
			(effects
				(font
					(size 1.27 1.27)
					(thickness 0.15)
				)
				(justify left bottom)
				(hide yes)
			)
		)
		(property "License" "Apache-2.0"
			(at 114.3 232.41 0)
			(effects
				(font
					(size 1.27 1.27)
					(thickness 0.15)
				)
				(justify left bottom)
				(hide yes)
			)
		)
		(property "Author" "Antmicro"
			(at 116.84 232.41 0)
			(effects
				(font
					(size 1.27 1.27)
					(thickness 0.15)
				)
				(justify left bottom)
				(hide yes)
			)
		)
		(property "Val" "100k"
			(at 87.63 251.46 90)
			(effects
				(font
					(size 1.27 1.27)
					(thickness 0.15)
				)
				(justify left)
			)
		)
		(property "Tolerance" "1%"
			(at 99.06 232.41 0)
			(effects
				(font
					(size 1.27 1.27)
				)
				(justify left bottom)
				(hide yes)
			)
		)
		(property "Public" "False"
			(at 119.38 232.41 0)
			(effects
				(font
					(size 1.27 1.27)
				)
				(justify left bottom)
				(hide yes)
			)
		)
		(pin "1"
		)
		(pin "2"
		)
		(instances
			(project "com-express-7-baseboard"
				(path ""
					(reference "R90")
					(unit 1)
				)
			)
		)
	)
	(symbol
		(lib_id "antmicropower:GND")
		(at 76.2 229.87 0)
		(mirror y)
		(unit 1)
		(exclude_from_sim no)
		(in_bom yes)
		(on_board yes)
		(dnp no)
		(property "Reference" "#PWR097"
			(at 67.31 232.41 0)
			(effects
				(font
					(size 1.27 1.27)
					(thickness 0.15)
				)
				(justify left bottom)
				(hide yes)
			)
		)
		(property "Value" "GND"
			(at 76.2 233.68 0)
			(effects
				(font
					(size 1.27 1.27)
					(thickness 0.15)
				)
			)
		)
		(property "Footprint" ""
			(at 67.31 237.49 0)
			(effects
				(font
					(size 1.27 1.27)
					(thickness 0.15)
				)
				(justify left bottom)
				(hide yes)
			)
		)
		(property "Datasheet" ""
			(at 67.31 242.57 0)
			(effects
				(font
					(size 1.27 1.27)
					(thickness 0.15)
				)
				(justify left bottom)
				(hide yes)
			)
		)
		(property "Description" ""
			(at 76.2 229.87 0)
			(effects
				(font
					(size 1.27 1.27)
				)
				(hide yes)
			)
		)
		(property "Author" "Antmicro"
			(at 67.31 237.49 0)
			(effects
				(font
					(size 1.27 1.27)
					(thickness 0.15)
				)
				(justify left bottom)
				(hide yes)
			)
		)
		(property "License" "Apache-2.0"
			(at 67.31 240.03 0)
			(effects
				(font
					(size 1.27 1.27)
					(thickness 0.15)
				)
				(justify left bottom)
				(hide yes)
			)
		)
		(pin "1"
		)
		(instances
			(project "com-express-7-baseboard"
				(path ""
					(reference "#PWR097")
					(unit 1)
				)
			)
		)
	)
	(symbol
		(lib_id "antmicroResistors0402:R_0R_0402")
		(at 378.46 219.71 0)
		(unit 1)
		(exclude_from_sim no)
		(in_bom yes)
		(on_board yes)
		(dnp no)
		(property "Reference" "R119"
			(at 381 214.63 0)
			(effects
				(font
					(size 1.27 1.27)
					(thickness 0.15)
				)
			)
		)
		(property "Value" "R_0R_0402"
			(at 398.78 232.41 0)
			(effects
				(font
					(size 1.27 1.27)
					(thickness 0.15)
				)
				(justify left bottom)
				(hide yes)
			)
		)
		(property "Footprint" "antmicro-footprints:R_0402_1005Metric"
			(at 398.78 234.95 0)
			(effects
				(font
					(size 1.27 1.27)
					(thickness 0.15)
				)
				(justify left bottom)
				(hide yes)
			)
		)
		(property "Datasheet" "https://industrial.panasonic.com/cdbs/www-data/pdf/RDA0000/AOA0000C301.pdf"
			(at 398.78 237.49 0)
			(effects
				(font
					(size 1.27 1.27)
					(thickness 0.15)
				)
				(justify left bottom)
				(hide yes)
			)
		)
		(property "Description" ""
			(at 378.46 219.71 0)
			(effects
				(font
					(size 1.27 1.27)
				)
				(hide yes)
			)
		)
		(property "MPN" "ERJ2GE0R00X"
			(at 398.78 240.03 0)
			(effects
				(font
					(size 1.27 1.27)
					(thickness 0.15)
				)
				(justify left bottom)
				(hide yes)
			)
		)
		(property "Manufacturer" "Panasonic"
			(at 398.78 242.57 0)
			(effects
				(font
					(size 1.27 1.27)
					(thickness 0.15)
				)
				(justify left bottom)
				(hide yes)
			)
		)
		(property "License" "Apache-2.0"
			(at 398.78 245.11 0)
			(effects
				(font
					(size 1.27 1.27)
					(thickness 0.15)
				)
				(justify left bottom)
				(hide yes)
			)
		)
		(property "Author" "Antmicro"
			(at 398.78 247.65 0)
			(effects
				(font
					(size 1.27 1.27)
					(thickness 0.15)
				)
				(justify left bottom)
				(hide yes)
			)
		)
		(property "Val" "0R"
			(at 381 217.17 0)
			(effects
				(font
					(size 1.27 1.27)
					(thickness 0.15)
				)
			)
		)
		(property "Tolerance" "~"
			(at 398.78 229.87 0)
			(effects
				(font
					(size 1.27 1.27)
				)
				(justify left bottom)
				(hide yes)
			)
		)
		(property "Current" "1A"
			(at 398.78 250.19 0)
			(effects
				(font
					(size 1.27 1.27)
					(thickness 0.15)
				)
				(justify left bottom)
				(hide yes)
			)
		)
		(property "Public" "False"
			(at 398.78 250.19 0)
			(effects
				(font
					(size 1.27 1.27)
				)
				(justify left bottom)
				(hide yes)
			)
		)
		(pin "1"
		)
		(pin "2"
		)
		(instances
			(project "com-express-7-baseboard"
				(path ""
					(reference "R119")
					(unit 1)
				)
			)
		)
	)
	(symbol
		(lib_id "antmicroCapacitors0402:C_1u_0402")
		(at 199.39 139.7 90)
		(unit 1)
		(exclude_from_sim no)
		(in_bom yes)
		(on_board yes)
		(dnp no)
		(property "Reference" "C57"
			(at 201.93 135.8835 90)
			(effects
				(font
					(size 1.27 1.27)
					(thickness 0.15)
				)
				(justify right)
			)
		)
		(property "Value" "C_1u_0402"
			(at 209.55 119.38 0)
			(effects
				(font
					(size 1.27 1.27)
					(thickness 0.15)
				)
				(justify left bottom)
				(hide yes)
			)
		)
		(property "Footprint" "antmicro-footprints:C_0402_1005Metric"
			(at 212.09 119.38 0)
			(effects
				(font
					(size 1.27 1.27)
					(thickness 0.15)
				)
				(justify left bottom)
				(hide yes)
			)
		)
		(property "Datasheet" "https://product.tdk.com/en/search/capacitor/ceramic/mlcc/info?part_no=C1005X6S1A105K050BC"
			(at 214.63 119.38 0)
			(effects
				(font
					(size 1.27 1.27)
					(thickness 0.15)
				)
				(justify left bottom)
				(hide yes)
			)
		)
		(property "Description" ""
			(at 199.39 139.7 0)
			(effects
				(font
					(size 1.27 1.27)
				)
				(hide yes)
			)
		)
		(property "MPN" "C1005X6S1A105K050BC"
			(at 217.17 119.38 0)
			(effects
				(font
					(size 1.27 1.27)
					(thickness 0.15)
				)
				(justify left bottom)
				(hide yes)
			)
		)
		(property "Manufacturer" "TDK"
			(at 219.71 119.38 0)
			(effects
				(font
					(size 1.27 1.27)
					(thickness 0.15)
				)
				(justify left bottom)
				(hide yes)
			)
		)
		(property "License" "Apache-2.0"
			(at 222.25 119.38 0)
			(effects
				(font
					(size 1.27 1.27)
					(thickness 0.15)
				)
				(justify left bottom)
				(hide yes)
			)
		)
		(property "Author" "Antmicro"
			(at 224.79 119.38 0)
			(effects
				(font
					(size 1.27 1.27)
					(thickness 0.15)
				)
				(justify left bottom)
				(hide yes)
			)
		)
		(property "Val" "1u"
			(at 201.93 138.4235 90)
			(effects
				(font
					(size 1.27 1.27)
					(thickness 0.15)
				)
				(justify right)
			)
		)
		(property "Voltage" ""
			(at 227.33 119.38 0)
			(effects
				(font
					(size 1.27 1.27)
				)
				(justify left bottom)
				(hide yes)
			)
		)
		(property "Dielectric" ""
			(at 229.87 119.38 0)
			(effects
				(font
					(size 1.27 1.27)
				)
				(justify left bottom)
				(hide yes)
			)
		)
		(property "Public" "False"
			(at 232.41 119.38 0)
			(effects
				(font
					(size 1.27 1.27)
				)
				(justify left bottom)
				(hide yes)
			)
		)
		(pin "1"
		)
		(pin "2"
		)
		(instances
			(project "com-express-7-baseboard"
				(path ""
					(reference "C57")
					(unit 1)
				)
			)
		)
	)
	(symbol
		(lib_id "antmicroResistors0402:R_10k_0402")
		(at 73.66 129.54 180)
		(unit 1)
		(exclude_from_sim no)
		(in_bom yes)
		(on_board yes)
		(dnp no)
		(property "Reference" "R86"
			(at 71.12 127.635 0)
			(effects
				(font
					(size 1.27 1.27)
					(thickness 0.15)
				)
			)
		)
		(property "Value" "R_10k_0402"
			(at 53.34 116.84 0)
			(effects
				(font
					(size 1.27 1.27)
					(thickness 0.15)
				)
				(justify left bottom)
				(hide yes)
			)
		)
		(property "Footprint" "antmicro-footprints:R_0402_1005Metric"
			(at 53.34 114.3 0)
			(effects
				(font
					(size 1.27 1.27)
					(thickness 0.15)
				)
				(justify left bottom)
				(hide yes)
			)
		)
		(property "Datasheet" "https://www.bourns.com/docs/product-datasheets/cr.pdf"
			(at 53.34 111.76 0)
			(effects
				(font
					(size 1.27 1.27)
					(thickness 0.15)
				)
				(justify left bottom)
				(hide yes)
			)
		)
		(property "Description" ""
			(at 73.66 129.54 0)
			(effects
				(font
					(size 1.27 1.27)
				)
				(hide yes)
			)
		)
		(property "MPN" "CR0402-FX-1002GLF"
			(at 53.34 109.22 0)
			(effects
				(font
					(size 1.27 1.27)
					(thickness 0.15)
				)
				(justify left bottom)
				(hide yes)
			)
		)
		(property "Manufacturer" "Bourns"
			(at 53.34 106.68 0)
			(effects
				(font
					(size 1.27 1.27)
					(thickness 0.15)
				)
				(justify left bottom)
				(hide yes)
			)
		)
		(property "License" "Apache-2.0"
			(at 53.34 104.14 0)
			(effects
				(font
					(size 1.27 1.27)
					(thickness 0.15)
				)
				(justify left bottom)
				(hide yes)
			)
		)
		(property "Author" "Antmicro"
			(at 53.34 101.6 0)
			(effects
				(font
					(size 1.27 1.27)
					(thickness 0.15)
				)
				(justify left bottom)
				(hide yes)
			)
		)
		(property "Val" "10k"
			(at 71.12 131.445 0)
			(effects
				(font
					(size 1.27 1.27)
					(thickness 0.15)
				)
			)
		)
		(property "Tolerance" "1%"
			(at 53.34 119.38 0)
			(effects
				(font
					(size 1.27 1.27)
				)
				(justify left bottom)
				(hide yes)
			)
		)
		(property "Public" "False"
			(at 53.34 99.06 0)
			(effects
				(font
					(size 1.27 1.27)
				)
				(justify left bottom)
				(hide yes)
			)
		)
		(pin "2"
		)
		(pin "1"
		)
		(instances
			(project "com-express-7-baseboard"
				(path ""
					(reference "R86")
					(unit 1)
				)
			)
		)
	)
	(symbol
		(lib_id "antmicropower:GND")
		(at 248.92 67.31 0)
		(unit 1)
		(exclude_from_sim no)
		(in_bom yes)
		(on_board yes)
		(dnp no)
		(property "Reference" "#PWR0133"
			(at 257.81 69.85 0)
			(effects
				(font
					(size 1.27 1.27)
					(thickness 0.15)
				)
				(justify left bottom)
				(hide yes)
			)
		)
		(property "Value" "GND"
			(at 248.92 71.12 0)
			(effects
				(font
					(size 1.27 1.27)
					(thickness 0.15)
				)
			)
		)
		(property "Footprint" ""
			(at 257.81 74.93 0)
			(effects
				(font
					(size 1.27 1.27)
					(thickness 0.15)
				)
				(justify left bottom)
				(hide yes)
			)
		)
		(property "Datasheet" ""
			(at 257.81 80.01 0)
			(effects
				(font
					(size 1.27 1.27)
					(thickness 0.15)
				)
				(justify left bottom)
				(hide yes)
			)
		)
		(property "Description" ""
			(at 248.92 67.31 0)
			(effects
				(font
					(size 1.27 1.27)
				)
				(hide yes)
			)
		)
		(property "Author" "Antmicro"
			(at 257.81 74.93 0)
			(effects
				(font
					(size 1.27 1.27)
					(thickness 0.15)
				)
				(justify left bottom)
				(hide yes)
			)
		)
		(property "License" "Apache-2.0"
			(at 257.81 77.47 0)
			(effects
				(font
					(size 1.27 1.27)
					(thickness 0.15)
				)
				(justify left bottom)
				(hide yes)
			)
		)
		(pin "1"
		)
		(instances
			(project "com-express-7-baseboard"
				(path ""
					(reference "#PWR0133")
					(unit 1)
				)
			)
		)
	)
	(symbol
		(lib_id "antmicroResistors0402:R_68k_0402")
		(at 139.7 135.89 90)
		(unit 1)
		(exclude_from_sim no)
		(in_bom yes)
		(on_board yes)
		(dnp no)
		(fields_autoplaced yes)
		(property "Reference" "R99"
			(at 142.24 132.0799 90)
			(effects
				(font
					(size 1.27 1.27)
					(thickness 0.15)
				)
				(justify right)
			)
		)
		(property "Value" "R_68k_0402"
			(at 152.4 115.57 0)
			(effects
				(font
					(size 1.27 1.27)
					(thickness 0.15)
				)
				(justify left bottom)
				(hide yes)
			)
		)
		(property "Footprint" "antmicro-footprints:R_0402_1005Metric"
			(at 154.94 115.57 0)
			(effects
				(font
					(size 1.27 1.27)
					(thickness 0.15)
				)
				(justify left bottom)
				(hide yes)
			)
		)
		(property "Datasheet" "https://www.bourns.com/docs/product-datasheets/cr.pdf"
			(at 157.48 115.57 0)
			(effects
				(font
					(size 1.27 1.27)
					(thickness 0.15)
				)
				(justify left bottom)
				(hide yes)
			)
		)
		(property "Description" ""
			(at 139.7 135.89 0)
			(effects
				(font
					(size 1.27 1.27)
				)
				(hide yes)
			)
		)
		(property "MPN" "CR0402-FX-6802GLF"
			(at 160.02 115.57 0)
			(effects
				(font
					(size 1.27 1.27)
					(thickness 0.15)
				)
				(justify left bottom)
				(hide yes)
			)
		)
		(property "Manufacturer" "Bourns"
			(at 162.56 115.57 0)
			(effects
				(font
					(size 1.27 1.27)
					(thickness 0.15)
				)
				(justify left bottom)
				(hide yes)
			)
		)
		(property "License" "Apache-2.0"
			(at 165.1 115.57 0)
			(effects
				(font
					(size 1.27 1.27)
					(thickness 0.15)
				)
				(justify left bottom)
				(hide yes)
			)
		)
		(property "Author" "Antmicro"
			(at 167.64 115.57 0)
			(effects
				(font
					(size 1.27 1.27)
					(thickness 0.15)
				)
				(justify left bottom)
				(hide yes)
			)
		)
		(property "Val" "68k"
			(at 142.24 134.6199 90)
			(effects
				(font
					(size 1.27 1.27)
					(thickness 0.15)
				)
				(justify right)
			)
		)
		(property "Tolerance" "1%"
			(at 149.86 115.57 0)
			(effects
				(font
					(size 1.27 1.27)
				)
				(justify left bottom)
				(hide yes)
			)
		)
		(property "Public" "False"
			(at 170.18 115.57 0)
			(effects
				(font
					(size 1.27 1.27)
				)
				(justify left bottom)
				(hide yes)
			)
		)
		(pin "2"
		)
		(pin "1"
		)
		(instances
			(project "com-express-7-baseboard"
				(path ""
					(reference "R99")
					(unit 1)
				)
			)
		)
	)
	(symbol
		(lib_id "antmicropower:GND")
		(at 266.7 140.97 0)
		(unit 1)
		(exclude_from_sim no)
		(in_bom yes)
		(on_board yes)
		(dnp no)
		(property "Reference" "#PWR0132"
			(at 275.59 143.51 0)
			(effects
				(font
					(size 1.27 1.27)
					(thickness 0.15)
				)
				(justify left bottom)
				(hide yes)
			)
		)
		(property "Value" "GND"
			(at 266.7 144.78 0)
			(effects
				(font
					(size 1.27 1.27)
					(thickness 0.15)
				)
			)
		)
		(property "Footprint" ""
			(at 275.59 148.59 0)
			(effects
				(font
					(size 1.27 1.27)
					(thickness 0.15)
				)
				(justify left bottom)
				(hide yes)
			)
		)
		(property "Datasheet" ""
			(at 275.59 153.67 0)
			(effects
				(font
					(size 1.27 1.27)
					(thickness 0.15)
				)
				(justify left bottom)
				(hide yes)
			)
		)
		(property "Description" ""
			(at 266.7 140.97 0)
			(effects
				(font
					(size 1.27 1.27)
				)
				(hide yes)
			)
		)
		(property "Author" "Antmicro"
			(at 275.59 148.59 0)
			(effects
				(font
					(size 1.27 1.27)
					(thickness 0.15)
				)
				(justify left bottom)
				(hide yes)
			)
		)
		(property "License" "Apache-2.0"
			(at 275.59 151.13 0)
			(effects
				(font
					(size 1.27 1.27)
					(thickness 0.15)
				)
				(justify left bottom)
				(hide yes)
			)
		)
		(pin "1"
		)
		(instances
			(project "com-express-7-baseboard"
				(path ""
					(reference "#PWR0132")
					(unit 1)
				)
			)
		)
	)
	(symbol
		(lib_id "antmicropower:+3V3_AON")
		(at 345.44 76.2 0)
		(unit 1)
		(exclude_from_sim no)
		(in_bom yes)
		(on_board yes)
		(dnp no)
		(property "Reference" "#PWR0446"
			(at 345.44 80.01 0)
			(effects
				(font
					(size 1.27 1.27)
				)
				(hide yes)
			)
		)
		(property "Value" "+3V3_AON"
			(at 345.44 72.39 0)
			(effects
				(font
					(size 1.27 1.27)
				)
			)
		)
		(property "Footprint" ""
			(at 345.44 76.2 0)
			(effects
				(font
					(size 1.27 1.27)
				)
				(hide yes)
			)
		)
		(property "Datasheet" ""
			(at 345.44 76.2 0)
			(effects
				(font
					(size 1.27 1.27)
				)
				(hide yes)
			)
		)
		(property "Description" ""
			(at 345.44 76.2 0)
			(effects
				(font
					(size 1.27 1.27)
				)
				(hide yes)
			)
		)
		(pin "1"
		)
		(instances
			(project "com-express-7-baseboard"
				(path ""
					(reference "#PWR0446")
					(unit 1)
				)
			)
		)
	)
	(symbol
		(lib_id "antmicropower:GND")
		(at 368.3 88.9 0)
		(unit 1)
		(exclude_from_sim no)
		(in_bom yes)
		(on_board yes)
		(dnp no)
		(property "Reference" "#PWR0149"
			(at 377.19 91.44 0)
			(effects
				(font
					(size 1.27 1.27)
					(thickness 0.15)
				)
				(justify left bottom)
				(hide yes)
			)
		)
		(property "Value" "GND"
			(at 368.3 92.71 0)
			(effects
				(font
					(size 1.27 1.27)
					(thickness 0.15)
				)
			)
		)
		(property "Footprint" ""
			(at 377.19 96.52 0)
			(effects
				(font
					(size 1.27 1.27)
					(thickness 0.15)
				)
				(justify left bottom)
				(hide yes)
			)
		)
		(property "Datasheet" ""
			(at 377.19 101.6 0)
			(effects
				(font
					(size 1.27 1.27)
					(thickness 0.15)
				)
				(justify left bottom)
				(hide yes)
			)
		)
		(property "Description" ""
			(at 368.3 88.9 0)
			(effects
				(font
					(size 1.27 1.27)
				)
				(hide yes)
			)
		)
		(property "Author" "Antmicro"
			(at 377.19 96.52 0)
			(effects
				(font
					(size 1.27 1.27)
					(thickness 0.15)
				)
				(justify left bottom)
				(hide yes)
			)
		)
		(property "License" "Apache-2.0"
			(at 377.19 99.06 0)
			(effects
				(font
					(size 1.27 1.27)
					(thickness 0.15)
				)
				(justify left bottom)
				(hide yes)
			)
		)
		(pin "1"
		)
		(instances
			(project "com-express-7-baseboard"
				(path ""
					(reference "#PWR0149")
					(unit 1)
				)
			)
		)
	)
	(symbol
		(lib_id "antmicroCapacitors0402:C_100n_0402")
		(at 340.36 85.09 90)
		(unit 1)
		(exclude_from_sim no)
		(in_bom yes)
		(on_board yes)
		(dnp no)
		(property "Reference" "C205"
			(at 340.995 80.645 90)
			(effects
				(font
					(size 1.27 1.27)
					(thickness 0.15)
				)
				(justify right)
			)
		)
		(property "Value" "C_100n_0402"
			(at 350.52 64.77 0)
			(effects
				(font
					(size 1.27 1.27)
					(thickness 0.15)
				)
				(justify left bottom)
				(hide yes)
			)
		)
		(property "Footprint" "antmicro-footprints:C_0402_1005Metric"
			(at 353.06 64.77 0)
			(effects
				(font
					(size 1.27 1.27)
					(thickness 0.15)
				)
				(justify left bottom)
				(hide yes)
			)
		)
		(property "Datasheet" "https://www.murata.com/products/productdetail?partno=GRM155R61H104KE14%23"
			(at 355.6 64.77 0)
			(effects
				(font
					(size 1.27 1.27)
					(thickness 0.15)
				)
				(justify left bottom)
				(hide yes)
			)
		)
		(property "Description" ""
			(at 340.36 85.09 0)
			(effects
				(font
					(size 1.27 1.27)
				)
				(hide yes)
			)
		)
		(property "MPN" "GRM155R61H104KE14D"
			(at 358.14 64.77 0)
			(effects
				(font
					(size 1.27 1.27)
					(thickness 0.15)
				)
				(justify left bottom)
				(hide yes)
			)
		)
		(property "Manufacturer" "Murata"
			(at 360.68 64.77 0)
			(effects
				(font
					(size 1.27 1.27)
					(thickness 0.15)
				)
				(justify left bottom)
				(hide yes)
			)
		)
		(property "License" "Apache-2.0"
			(at 363.22 64.77 0)
			(effects
				(font
					(size 1.27 1.27)
					(thickness 0.15)
				)
				(justify left bottom)
				(hide yes)
			)
		)
		(property "Author" "Antmicro"
			(at 365.76 64.77 0)
			(effects
				(font
					(size 1.27 1.27)
					(thickness 0.15)
				)
				(justify left bottom)
				(hide yes)
			)
		)
		(property "Val" "100n"
			(at 340.995 84.455 90)
			(effects
				(font
					(size 1.27 1.27)
					(thickness 0.15)
				)
				(justify right)
			)
		)
		(property "Voltage" "50V"
			(at 368.3 64.77 0)
			(effects
				(font
					(size 1.27 1.27)
				)
				(justify left bottom)
				(hide yes)
			)
		)
		(property "Dielectric" "X5R"
			(at 370.84 64.77 0)
			(effects
				(font
					(size 1.27 1.27)
				)
				(justify left bottom)
				(hide yes)
			)
		)
		(property "Public" "False"
			(at 373.38 64.77 0)
			(effects
				(font
					(size 1.27 1.27)
				)
				(justify left bottom)
				(hide yes)
			)
		)
		(pin "1"
		)
		(pin "2"
		)
		(instances
			(project "com-express-7-baseboard"
				(path ""
					(reference "C205")
					(unit 1)
				)
			)
		)
	)
	(symbol
		(lib_id "antmicropower:+5V_AON")
		(at 363.22 53.34 0)
		(unit 1)
		(exclude_from_sim no)
		(in_bom yes)
		(on_board yes)
		(dnp no)
		(property "Reference" "#PWR0145"
			(at 363.22 57.15 0)
			(effects
				(font
					(size 1.27 1.27)
				)
				(hide yes)
			)
		)
		(property "Value" "+5V_AON"
			(at 363.22 49.53 0)
			(effects
				(font
					(size 1.27 1.27)
				)
			)
		)
		(property "Footprint" ""
			(at 363.22 53.34 0)
			(effects
				(font
					(size 1.27 1.27)
				)
				(hide yes)
			)
		)
		(property "Datasheet" ""
			(at 363.22 53.34 0)
			(effects
				(font
					(size 1.27 1.27)
				)
				(hide yes)
			)
		)
		(property "Description" ""
			(at 363.22 53.34 0)
			(effects
				(font
					(size 1.27 1.27)
				)
				(hide yes)
			)
		)
		(pin "1"
		)
		(instances
			(project "com-express-7-baseboard"
				(path ""
					(reference "#PWR0145")
					(unit 1)
				)
			)
		)
	)
	(symbol
		(lib_id "antmicropower:GND")
		(at 290.83 69.85 0)
		(unit 1)
		(exclude_from_sim no)
		(in_bom yes)
		(on_board yes)
		(dnp no)
		(property "Reference" "#PWR0136"
			(at 299.72 72.39 0)
			(effects
				(font
					(size 1.27 1.27)
					(thickness 0.15)
				)
				(justify left bottom)
				(hide yes)
			)
		)
		(property "Value" "GND"
			(at 290.83 73.66 0)
			(effects
				(font
					(size 1.27 1.27)
					(thickness 0.15)
				)
			)
		)
		(property "Footprint" ""
			(at 299.72 77.47 0)
			(effects
				(font
					(size 1.27 1.27)
					(thickness 0.15)
				)
				(justify left bottom)
				(hide yes)
			)
		)
		(property "Datasheet" ""
			(at 299.72 82.55 0)
			(effects
				(font
					(size 1.27 1.27)
					(thickness 0.15)
				)
				(justify left bottom)
				(hide yes)
			)
		)
		(property "Description" ""
			(at 290.83 69.85 0)
			(effects
				(font
					(size 1.27 1.27)
				)
				(hide yes)
			)
		)
		(property "Author" "Antmicro"
			(at 299.72 77.47 0)
			(effects
				(font
					(size 1.27 1.27)
					(thickness 0.15)
				)
				(justify left bottom)
				(hide yes)
			)
		)
		(property "License" "Apache-2.0"
			(at 299.72 80.01 0)
			(effects
				(font
					(size 1.27 1.27)
					(thickness 0.15)
				)
				(justify left bottom)
				(hide yes)
			)
		)
		(pin "1"
		)
		(instances
			(project "com-express-7-baseboard"
				(path ""
					(reference "#PWR0136")
					(unit 1)
				)
			)
		)
	)
	(symbol
		(lib_id "antmicropower:GND")
		(at 163.83 233.68 0)
		(unit 1)
		(exclude_from_sim no)
		(in_bom yes)
		(on_board yes)
		(dnp no)
		(property "Reference" "#PWR0119"
			(at 172.72 236.22 0)
			(effects
				(font
					(size 1.27 1.27)
					(thickness 0.15)
				)
				(justify left bottom)
				(hide yes)
			)
		)
		(property "Value" "GND"
			(at 163.83 237.49 0)
			(effects
				(font
					(size 1.27 1.27)
					(thickness 0.15)
				)
			)
		)
		(property "Footprint" ""
			(at 172.72 241.3 0)
			(effects
				(font
					(size 1.27 1.27)
					(thickness 0.15)
				)
				(justify left bottom)
				(hide yes)
			)
		)
		(property "Datasheet" ""
			(at 172.72 246.38 0)
			(effects
				(font
					(size 1.27 1.27)
					(thickness 0.15)
				)
				(justify left bottom)
				(hide yes)
			)
		)
		(property "Description" ""
			(at 163.83 233.68 0)
			(effects
				(font
					(size 1.27 1.27)
				)
				(hide yes)
			)
		)
		(property "Author" "Antmicro"
			(at 172.72 241.3 0)
			(effects
				(font
					(size 1.27 1.27)
					(thickness 0.15)
				)
				(justify left bottom)
				(hide yes)
			)
		)
		(property "License" "Apache-2.0"
			(at 172.72 243.84 0)
			(effects
				(font
					(size 1.27 1.27)
					(thickness 0.15)
				)
				(justify left bottom)
				(hide yes)
			)
		)
		(pin "1"
		)
		(instances
			(project "com-express-7-baseboard"
				(path ""
					(reference "#PWR0119")
					(unit 1)
				)
			)
		)
	)
	(symbol
		(lib_id "antmicropower:GND")
		(at 340.36 88.9 0)
		(unit 1)
		(exclude_from_sim no)
		(in_bom yes)
		(on_board yes)
		(dnp no)
		(property "Reference" "#PWR0445"
			(at 349.25 91.44 0)
			(effects
				(font
					(size 1.27 1.27)
					(thickness 0.15)
				)
				(justify left bottom)
				(hide yes)
			)
		)
		(property "Value" "GND"
			(at 340.36 92.71 0)
			(effects
				(font
					(size 1.27 1.27)
					(thickness 0.15)
				)
			)
		)
		(property "Footprint" ""
			(at 349.25 96.52 0)
			(effects
				(font
					(size 1.27 1.27)
					(thickness 0.15)
				)
				(justify left bottom)
				(hide yes)
			)
		)
		(property "Datasheet" ""
			(at 349.25 101.6 0)
			(effects
				(font
					(size 1.27 1.27)
					(thickness 0.15)
				)
				(justify left bottom)
				(hide yes)
			)
		)
		(property "Description" ""
			(at 340.36 88.9 0)
			(effects
				(font
					(size 1.27 1.27)
				)
				(hide yes)
			)
		)
		(property "Author" "Antmicro"
			(at 349.25 96.52 0)
			(effects
				(font
					(size 1.27 1.27)
					(thickness 0.15)
				)
				(justify left bottom)
				(hide yes)
			)
		)
		(property "License" "Apache-2.0"
			(at 349.25 99.06 0)
			(effects
				(font
					(size 1.27 1.27)
					(thickness 0.15)
				)
				(justify left bottom)
				(hide yes)
			)
		)
		(pin "1"
		)
		(instances
			(project "com-express-7-baseboard"
				(path ""
					(reference "#PWR0445")
					(unit 1)
				)
			)
		)
	)
	(symbol
		(lib_id "antmicropower:+12V_AON")
		(at 48.26 123.19 0)
		(unit 1)
		(exclude_from_sim no)
		(in_bom yes)
		(on_board yes)
		(dnp no)
		(fields_autoplaced yes)
		(property "Reference" "#PWR088"
			(at 48.26 127 0)
			(effects
				(font
					(size 1.27 1.27)
				)
				(hide yes)
			)
		)
		(property "Value" "+12V_AON"
			(at 48.26 118.11 0)
			(effects
				(font
					(size 1.27 1.27)
				)
			)
		)
		(property "Footprint" ""
			(at 48.26 123.19 0)
			(effects
				(font
					(size 1.27 1.27)
				)
				(hide yes)
			)
		)
		(property "Datasheet" ""
			(at 48.26 123.19 0)
			(effects
				(font
					(size 1.27 1.27)
				)
				(hide yes)
			)
		)
		(property "Description" ""
			(at 48.26 123.19 0)
			(effects
				(font
					(size 1.27 1.27)
				)
				(hide yes)
			)
		)
		(pin "1"
		)
		(instances
			(project "com-express-7-baseboard"
				(path ""
					(reference "#PWR088")
					(unit 1)
				)
			)
		)
	)
	(symbol
		(lib_id "antmicropower:GND")
		(at 124.46 68.58 0)
		(mirror y)
		(unit 1)
		(exclude_from_sim no)
		(in_bom yes)
		(on_board yes)
		(dnp no)
		(property "Reference" "#PWR0108"
			(at 115.57 71.12 0)
			(effects
				(font
					(size 1.27 1.27)
					(thickness 0.15)
				)
				(justify left bottom)
				(hide yes)
			)
		)
		(property "Value" "GND"
			(at 124.46 72.39 0)
			(effects
				(font
					(size 1.27 1.27)
					(thickness 0.15)
				)
			)
		)
		(property "Footprint" ""
			(at 115.57 76.2 0)
			(effects
				(font
					(size 1.27 1.27)
					(thickness 0.15)
				)
				(justify left bottom)
				(hide yes)
			)
		)
		(property "Datasheet" ""
			(at 115.57 81.28 0)
			(effects
				(font
					(size 1.27 1.27)
					(thickness 0.15)
				)
				(justify left bottom)
				(hide yes)
			)
		)
		(property "Description" ""
			(at 124.46 68.58 0)
			(effects
				(font
					(size 1.27 1.27)
				)
				(hide yes)
			)
		)
		(property "Author" "Antmicro"
			(at 115.57 76.2 0)
			(effects
				(font
					(size 1.27 1.27)
					(thickness 0.15)
				)
				(justify left bottom)
				(hide yes)
			)
		)
		(property "License" "Apache-2.0"
			(at 115.57 78.74 0)
			(effects
				(font
					(size 1.27 1.27)
					(thickness 0.15)
				)
				(justify left bottom)
				(hide yes)
			)
		)
		(pin "1"
		)
		(instances
			(project "com-express-7-baseboard"
				(path ""
					(reference "#PWR0108")
					(unit 1)
				)
			)
		)
	)
	(symbol
		(lib_id "antmicroCapacitors0402:C_1u_0402")
		(at 358.14 66.04 90)
		(unit 1)
		(exclude_from_sim no)
		(in_bom yes)
		(on_board yes)
		(dnp no)
		(fields_autoplaced yes)
		(property "Reference" "C67"
			(at 360.68 62.2235 90)
			(effects
				(font
					(size 1.27 1.27)
					(thickness 0.15)
				)
				(justify right)
			)
		)
		(property "Value" "C_1u_0402"
			(at 368.3 45.72 0)
			(effects
				(font
					(size 1.27 1.27)
					(thickness 0.15)
				)
				(justify left bottom)
				(hide yes)
			)
		)
		(property "Footprint" "antmicro-footprints:C_0402_1005Metric"
			(at 370.84 45.72 0)
			(effects
				(font
					(size 1.27 1.27)
					(thickness 0.15)
				)
				(justify left bottom)
				(hide yes)
			)
		)
		(property "Datasheet" "https://product.tdk.com/en/search/capacitor/ceramic/mlcc/info?part_no=C1005X6S1A105K050BC"
			(at 373.38 45.72 0)
			(effects
				(font
					(size 1.27 1.27)
					(thickness 0.15)
				)
				(justify left bottom)
				(hide yes)
			)
		)
		(property "Description" ""
			(at 358.14 66.04 0)
			(effects
				(font
					(size 1.27 1.27)
				)
				(hide yes)
			)
		)
		(property "MPN" "C1005X6S1A105K050BC"
			(at 375.92 45.72 0)
			(effects
				(font
					(size 1.27 1.27)
					(thickness 0.15)
				)
				(justify left bottom)
				(hide yes)
			)
		)
		(property "Manufacturer" "TDK"
			(at 378.46 45.72 0)
			(effects
				(font
					(size 1.27 1.27)
					(thickness 0.15)
				)
				(justify left bottom)
				(hide yes)
			)
		)
		(property "License" "Apache-2.0"
			(at 381 45.72 0)
			(effects
				(font
					(size 1.27 1.27)
					(thickness 0.15)
				)
				(justify left bottom)
				(hide yes)
			)
		)
		(property "Author" "Antmicro"
			(at 383.54 45.72 0)
			(effects
				(font
					(size 1.27 1.27)
					(thickness 0.15)
				)
				(justify left bottom)
				(hide yes)
			)
		)
		(property "Val" "1u"
			(at 360.68 64.7635 90)
			(effects
				(font
					(size 1.27 1.27)
					(thickness 0.15)
				)
				(justify right)
			)
		)
		(property "Voltage" ""
			(at 386.08 45.72 0)
			(effects
				(font
					(size 1.27 1.27)
				)
				(justify left bottom)
				(hide yes)
			)
		)
		(property "Dielectric" ""
			(at 388.62 45.72 0)
			(effects
				(font
					(size 1.27 1.27)
				)
				(justify left bottom)
				(hide yes)
			)
		)
		(property "Public" "False"
			(at 391.16 45.72 0)
			(effects
				(font
					(size 1.27 1.27)
				)
				(justify left bottom)
				(hide yes)
			)
		)
		(pin "1"
		)
		(pin "2"
		)
		(instances
			(project "com-express-7-baseboard"
				(path ""
					(reference "C67")
					(unit 1)
				)
			)
		)
	)
	(symbol
		(lib_id "antmicroCapacitors0402:C_1u_0402")
		(at 116.84 231.14 90)
		(unit 1)
		(exclude_from_sim no)
		(in_bom yes)
		(on_board yes)
		(dnp no)
		(fields_autoplaced yes)
		(property "Reference" "C46"
			(at 119.38 227.3235 90)
			(effects
				(font
					(size 1.27 1.27)
					(thickness 0.15)
				)
				(justify right)
			)
		)
		(property "Value" "C_1u_0402"
			(at 127 210.82 0)
			(effects
				(font
					(size 1.27 1.27)
					(thickness 0.15)
				)
				(justify left bottom)
				(hide yes)
			)
		)
		(property "Footprint" "antmicro-footprints:C_0402_1005Metric"
			(at 129.54 210.82 0)
			(effects
				(font
					(size 1.27 1.27)
					(thickness 0.15)
				)
				(justify left bottom)
				(hide yes)
			)
		)
		(property "Datasheet" "https://product.tdk.com/en/search/capacitor/ceramic/mlcc/info?part_no=C1005X6S1A105K050BC"
			(at 132.08 210.82 0)
			(effects
				(font
					(size 1.27 1.27)
					(thickness 0.15)
				)
				(justify left bottom)
				(hide yes)
			)
		)
		(property "Description" ""
			(at 116.84 231.14 0)
			(effects
				(font
					(size 1.27 1.27)
				)
				(hide yes)
			)
		)
		(property "MPN" "C1005X6S1A105K050BC"
			(at 134.62 210.82 0)
			(effects
				(font
					(size 1.27 1.27)
					(thickness 0.15)
				)
				(justify left bottom)
				(hide yes)
			)
		)
		(property "Manufacturer" "TDK"
			(at 137.16 210.82 0)
			(effects
				(font
					(size 1.27 1.27)
					(thickness 0.15)
				)
				(justify left bottom)
				(hide yes)
			)
		)
		(property "License" "Apache-2.0"
			(at 139.7 210.82 0)
			(effects
				(font
					(size 1.27 1.27)
					(thickness 0.15)
				)
				(justify left bottom)
				(hide yes)
			)
		)
		(property "Author" "Antmicro"
			(at 142.24 210.82 0)
			(effects
				(font
					(size 1.27 1.27)
					(thickness 0.15)
				)
				(justify left bottom)
				(hide yes)
			)
		)
		(property "Val" "1u"
			(at 119.38 229.8635 90)
			(effects
				(font
					(size 1.27 1.27)
					(thickness 0.15)
				)
				(justify right)
			)
		)
		(property "Voltage" ""
			(at 144.78 210.82 0)
			(effects
				(font
					(size 1.27 1.27)
				)
				(justify left bottom)
				(hide yes)
			)
		)
		(property "Dielectric" ""
			(at 147.32 210.82 0)
			(effects
				(font
					(size 1.27 1.27)
				)
				(justify left bottom)
				(hide yes)
			)
		)
		(property "Public" "False"
			(at 149.86 210.82 0)
			(effects
				(font
					(size 1.27 1.27)
				)
				(justify left bottom)
				(hide yes)
			)
		)
		(pin "1"
		)
		(pin "2"
		)
		(instances
			(project "com-express-7-baseboard"
				(path ""
					(reference "C46")
					(unit 1)
				)
			)
		)
	)
	(symbol
		(lib_id "antmicropower:+12V_AON")
		(at 271.78 234.95 0)
		(unit 1)
		(exclude_from_sim no)
		(in_bom yes)
		(on_board yes)
		(dnp no)
		(property "Reference" "#PWR0468"
			(at 271.78 238.76 0)
			(effects
				(font
					(size 1.27 1.27)
				)
				(hide yes)
			)
		)
		(property "Value" "+12V_AON"
			(at 271.78 231.14 0)
			(effects
				(font
					(size 1.27 1.27)
				)
			)
		)
		(property "Footprint" ""
			(at 271.78 234.95 0)
			(effects
				(font
					(size 1.27 1.27)
				)
				(hide yes)
			)
		)
		(property "Datasheet" ""
			(at 271.78 234.95 0)
			(effects
				(font
					(size 1.27 1.27)
				)
				(hide yes)
			)
		)
		(property "Description" ""
			(at 271.78 234.95 0)
			(effects
				(font
					(size 1.27 1.27)
				)
				(hide yes)
			)
		)
		(pin "1"
		)
		(instances
			(project "com-express-7-baseboard"
				(path ""
					(reference "#PWR0468")
					(unit 1)
				)
			)
		)
	)
	(symbol
		(lib_id "antmicroCapacitorspol:C_Pol_100u_10V_KEMET-T520-B")
		(at 160.02 54.61 270)
		(unit 1)
		(exclude_from_sim no)
		(in_bom yes)
		(on_board yes)
		(dnp no)
		(fields_autoplaced yes)
		(property "Reference" "C51"
			(at 162.56 54.0765 90)
			(effects
				(font
					(size 1.27 1.27)
					(thickness 0.15)
				)
				(justify left)
			)
		)
		(property "Value" "C_Pol_100u_10V_KEMET-T520-B"
			(at 157.48 68.58 0)
			(effects
				(font
					(size 1.27 1.27)
					(thickness 0.15)
				)
				(justify left bottom)
				(hide yes)
			)
		)
		(property "Footprint" "antmicro-footprints:C_Pol_EIA-B"
			(at 152.4 68.58 0)
			(effects
				(font
					(size 1.27 1.27)
					(thickness 0.15)
				)
				(justify left bottom)
				(hide yes)
			)
		)
		(property "Datasheet" "https://www.kemet.com/en/us/capacitors/product/T520B107M010ATE070.html"
			(at 149.86 68.58 0)
			(effects
				(font
					(size 1.27 1.27)
					(thickness 0.15)
				)
				(justify left bottom)
				(hide yes)
			)
		)
		(property "Description" ""
			(at 160.02 54.61 0)
			(effects
				(font
					(size 1.27 1.27)
				)
				(hide yes)
			)
		)
		(property "Val" "100u"
			(at 162.56 56.6165 90)
			(effects
				(font
					(size 1.27 1.27)
					(thickness 0.15)
				)
				(justify left)
			)
		)
		(property "MPN" "T520B107M010ATE070"
			(at 147.32 68.58 0)
			(effects
				(font
					(size 1.27 1.27)
					(thickness 0.15)
				)
				(justify left bottom)
				(hide yes)
			)
		)
		(property "Manufacturer" "KEMET"
			(at 144.78 68.58 0)
			(effects
				(font
					(size 1.27 1.27)
					(thickness 0.15)
				)
				(justify left bottom)
				(hide yes)
			)
		)
		(property "License" "Apache-2.0"
			(at 142.24 68.58 0)
			(effects
				(font
					(size 1.27 1.27)
					(thickness 0.15)
				)
				(justify left bottom)
				(hide yes)
			)
		)
		(property "Author" "Antmicro"
			(at 139.7 68.58 0)
			(effects
				(font
					(size 1.27 1.27)
					(thickness 0.15)
				)
				(justify left bottom)
				(hide yes)
			)
		)
		(property "Voltage" "10V"
			(at 162.56 59.1565 90)
			(effects
				(font
					(size 1.27 1.27)
				)
				(justify left)
			)
		)
		(property "Dielectric" "template_dielectric"
			(at 134.62 68.58 0)
			(effects
				(font
					(size 1.27 1.27)
				)
				(justify left bottom)
				(hide yes)
			)
		)
		(property "Public" "False"
			(at 132.08 68.58 0)
			(effects
				(font
					(size 1.27 1.27)
				)
				(justify left bottom)
				(hide yes)
			)
		)
		(pin "1"
		)
		(pin "2"
		)
		(instances
			(project "com-express-7-baseboard"
				(path ""
					(reference "C51")
					(unit 1)
				)
			)
		)
	)
	(symbol
		(lib_id "antmicropower:GND")
		(at 358.14 66.04 0)
		(unit 1)
		(exclude_from_sim no)
		(in_bom yes)
		(on_board yes)
		(dnp no)
		(property "Reference" "#PWR0146"
			(at 367.03 68.58 0)
			(effects
				(font
					(size 1.27 1.27)
					(thickness 0.15)
				)
				(justify left bottom)
				(hide yes)
			)
		)
		(property "Value" "GND"
			(at 358.14 69.85 0)
			(effects
				(font
					(size 1.27 1.27)
					(thickness 0.15)
				)
			)
		)
		(property "Footprint" ""
			(at 367.03 73.66 0)
			(effects
				(font
					(size 1.27 1.27)
					(thickness 0.15)
				)
				(justify left bottom)
				(hide yes)
			)
		)
		(property "Datasheet" ""
			(at 367.03 78.74 0)
			(effects
				(font
					(size 1.27 1.27)
					(thickness 0.15)
				)
				(justify left bottom)
				(hide yes)
			)
		)
		(property "Description" ""
			(at 358.14 66.04 0)
			(effects
				(font
					(size 1.27 1.27)
				)
				(hide yes)
			)
		)
		(property "Author" "Antmicro"
			(at 367.03 73.66 0)
			(effects
				(font
					(size 1.27 1.27)
					(thickness 0.15)
				)
				(justify left bottom)
				(hide yes)
			)
		)
		(property "License" "Apache-2.0"
			(at 367.03 76.2 0)
			(effects
				(font
					(size 1.27 1.27)
					(thickness 0.15)
				)
				(justify left bottom)
				(hide yes)
			)
		)
		(pin "1"
		)
		(instances
			(project "com-express-7-baseboard"
				(path ""
					(reference "#PWR0146")
					(unit 1)
				)
			)
		)
	)
	(symbol
		(lib_id "antmicroCapacitors0402:C_100n_0402")
		(at 163.83 233.68 90)
		(unit 1)
		(exclude_from_sim no)
		(in_bom yes)
		(on_board yes)
		(dnp no)
		(fields_autoplaced yes)
		(property "Reference" "C54"
			(at 166.37 229.8636 90)
			(effects
				(font
					(size 1.27 1.27)
					(thickness 0.15)
				)
				(justify right)
			)
		)
		(property "Value" "C_100n_0402"
			(at 173.99 213.36 0)
			(effects
				(font
					(size 1.27 1.27)
					(thickness 0.15)
				)
				(justify left bottom)
				(hide yes)
			)
		)
		(property "Footprint" "antmicro-footprints:C_0402_1005Metric"
			(at 176.53 213.36 0)
			(effects
				(font
					(size 1.27 1.27)
					(thickness 0.15)
				)
				(justify left bottom)
				(hide yes)
			)
		)
		(property "Datasheet" "https://www.murata.com/products/productdetail?partno=GRM155R61H104KE14%23"
			(at 179.07 213.36 0)
			(effects
				(font
					(size 1.27 1.27)
					(thickness 0.15)
				)
				(justify left bottom)
				(hide yes)
			)
		)
		(property "Description" ""
			(at 163.83 233.68 0)
			(effects
				(font
					(size 1.27 1.27)
				)
				(hide yes)
			)
		)
		(property "MPN" "GRM155R61H104KE14D"
			(at 181.61 213.36 0)
			(effects
				(font
					(size 1.27 1.27)
					(thickness 0.15)
				)
				(justify left bottom)
				(hide yes)
			)
		)
		(property "Manufacturer" "Murata"
			(at 184.15 213.36 0)
			(effects
				(font
					(size 1.27 1.27)
					(thickness 0.15)
				)
				(justify left bottom)
				(hide yes)
			)
		)
		(property "License" "Apache-2.0"
			(at 186.69 213.36 0)
			(effects
				(font
					(size 1.27 1.27)
					(thickness 0.15)
				)
				(justify left bottom)
				(hide yes)
			)
		)
		(property "Author" "Antmicro"
			(at 189.23 213.36 0)
			(effects
				(font
					(size 1.27 1.27)
					(thickness 0.15)
				)
				(justify left bottom)
				(hide yes)
			)
		)
		(property "Val" "100n"
			(at 166.37 232.4036 90)
			(effects
				(font
					(size 1.27 1.27)
					(thickness 0.15)
				)
				(justify right)
			)
		)
		(property "Voltage" "50V"
			(at 191.77 213.36 0)
			(effects
				(font
					(size 1.27 1.27)
				)
				(justify left bottom)
				(hide yes)
			)
		)
		(property "Dielectric" "X5R"
			(at 194.31 213.36 0)
			(effects
				(font
					(size 1.27 1.27)
				)
				(justify left bottom)
				(hide yes)
			)
		)
		(property "Public" "False"
			(at 196.85 213.36 0)
			(effects
				(font
					(size 1.27 1.27)
				)
				(justify left bottom)
				(hide yes)
			)
		)
		(pin "1"
		)
		(pin "2"
		)
		(instances
			(project "com-express-7-baseboard"
				(path ""
					(reference "C54")
					(unit 1)
				)
			)
		)
	)
	(symbol
		(lib_id "antmicropower:+12V")
		(at 116.84 220.98 0)
		(unit 1)
		(exclude_from_sim no)
		(in_bom yes)
		(on_board yes)
		(dnp no)
		(property "Reference" "#PWR0106"
			(at 116.84 224.79 0)
			(effects
				(font
					(size 1.27 1.27)
				)
				(hide yes)
			)
		)
		(property "Value" "+12V"
			(at 116.84 217.17 0)
			(effects
				(font
					(size 1.27 1.27)
				)
			)
		)
		(property "Footprint" ""
			(at 116.84 220.98 0)
			(effects
				(font
					(size 1.27 1.27)
				)
				(hide yes)
			)
		)
		(property "Datasheet" ""
			(at 116.84 220.98 0)
			(effects
				(font
					(size 1.27 1.27)
				)
				(hide yes)
			)
		)
		(property "Description" ""
			(at 116.84 220.98 0)
			(effects
				(font
					(size 1.27 1.27)
				)
				(hide yes)
			)
		)
		(pin "1"
		)
		(instances
			(project "com-express-7-baseboard"
				(path ""
					(reference "#PWR0106")
					(unit 1)
				)
			)
		)
	)
	(symbol
		(lib_id "antmicropower:PWR_FLAG")
		(at 388.62 219.71 270)
		(unit 1)
		(exclude_from_sim no)
		(in_bom yes)
		(on_board yes)
		(dnp no)
		(fields_autoplaced yes)
		(property "Reference" "#FLG014"
			(at 390.525 219.71 0)
			(effects
				(font
					(size 1.27 1.27)
				)
				(hide yes)
			)
		)
		(property "Value" "PWR_FLAG"
			(at 392.43 219.7099 90)
			(effects
				(font
					(size 1.27 1.27)
				)
				(justify left)
			)
		)
		(property "Footprint" ""
			(at 388.62 219.71 0)
			(effects
				(font
					(size 1.27 1.27)
				)
				(hide yes)
			)
		)
		(property "Datasheet" ""
			(at 388.62 219.71 0)
			(effects
				(font
					(size 1.27 1.27)
				)
				(hide yes)
			)
		)
		(property "Description" ""
			(at 388.62 219.71 0)
			(effects
				(font
					(size 1.27 1.27)
				)
				(hide yes)
			)
		)
		(pin "1"
		)
		(instances
			(project "com-express-7-baseboard"
				(path ""
					(reference "#FLG014")
					(unit 1)
				)
			)
		)
	)
	(symbol
		(lib_id "antmicroTransistorsFETsMOSFETsSingle:BSS138-7-F")
		(at 369.57 78.74 0)
		(unit 1)
		(exclude_from_sim no)
		(in_bom yes)
		(on_board yes)
		(dnp no)
		(property "Reference" "Q3"
			(at 381 74.93 0)
			(effects
				(font
					(size 1.27 1.27)
					(thickness 0.15)
				)
				(justify left)
			)
		)
		(property "Value" "BSS138-7-F"
			(at 381 77.47 0)
			(effects
				(font
					(size 1.27 1.27)
					(thickness 0.15)
				)
				(justify left)
				(hide yes)
			)
		)
		(property "Footprint" "antmicro-footprints:SOT-23-3"
			(at 392.43 86.36 0)
			(effects
				(font
					(size 1.27 1.27)
					(thickness 0.15)
				)
				(justify left bottom)
				(hide yes)
			)
		)
		(property "Datasheet" "https://www.diodes.com/assets/Datasheets/ds30144.pdf"
			(at 392.43 88.9 0)
			(effects
				(font
					(size 1.27 1.27)
					(thickness 0.15)
				)
				(justify left bottom)
				(hide yes)
			)
		)
		(property "Description" ""
			(at 369.57 78.74 0)
			(effects
				(font
					(size 1.27 1.27)
				)
				(hide yes)
			)
		)
		(property "MPN" "BSS138-7-F"
			(at 381 78.74 0)
			(effects
				(font
					(size 1.27 1.27)
					(thickness 0.15)
				)
				(justify left bottom)
			)
		)
		(property "Manufacturer" "Diodes Incorporated"
			(at 392.43 93.98 0)
			(effects
				(font
					(size 1.27 1.27)
					(thickness 0.15)
				)
				(justify left bottom)
				(hide yes)
			)
		)
		(property "Author" "Antmicro"
			(at 392.43 96.52 0)
			(effects
				(font
					(size 1.27 1.27)
					(thickness 0.15)
				)
				(justify left bottom)
				(hide yes)
			)
		)
		(property "License" "Apache-2.0"
			(at 392.43 99.06 0)
			(effects
				(font
					(size 1.27 1.27)
					(thickness 0.15)
				)
				(justify left bottom)
				(hide yes)
			)
		)
		(pin "1"
		)
		(pin "2"
		)
		(pin "3"
		)
		(instances
			(project "com-express-7-baseboard"
				(path ""
					(reference "Q3")
					(unit 1)
				)
			)
		)
	)
	(symbol
		(lib_id "antmicropower:GND")
		(at 228.6 59.69 0)
		(unit 1)
		(exclude_from_sim no)
		(in_bom yes)
		(on_board yes)
		(dnp no)
		(property "Reference" "#PWR0128"
			(at 237.49 62.23 0)
			(effects
				(font
					(size 1.27 1.27)
					(thickness 0.15)
				)
				(justify left bottom)
				(hide yes)
			)
		)
		(property "Value" "GND"
			(at 228.6 63.5 0)
			(effects
				(font
					(size 1.27 1.27)
					(thickness 0.15)
				)
			)
		)
		(property "Footprint" ""
			(at 237.49 67.31 0)
			(effects
				(font
					(size 1.27 1.27)
					(thickness 0.15)
				)
				(justify left bottom)
				(hide yes)
			)
		)
		(property "Datasheet" ""
			(at 237.49 72.39 0)
			(effects
				(font
					(size 1.27 1.27)
					(thickness 0.15)
				)
				(justify left bottom)
				(hide yes)
			)
		)
		(property "Description" ""
			(at 228.6 59.69 0)
			(effects
				(font
					(size 1.27 1.27)
				)
				(hide yes)
			)
		)
		(property "Author" "Antmicro"
			(at 237.49 67.31 0)
			(effects
				(font
					(size 1.27 1.27)
					(thickness 0.15)
				)
				(justify left bottom)
				(hide yes)
			)
		)
		(property "License" "Apache-2.0"
			(at 237.49 69.85 0)
			(effects
				(font
					(size 1.27 1.27)
					(thickness 0.15)
				)
				(justify left bottom)
				(hide yes)
			)
		)
		(pin "1"
		)
		(instances
			(project "com-express-7-baseboard"
				(path ""
					(reference "#PWR0128")
					(unit 1)
				)
			)
		)
	)
	(symbol
		(lib_id "antmicropower:GND")
		(at 171.45 167.64 0)
		(unit 1)
		(exclude_from_sim no)
		(in_bom yes)
		(on_board yes)
		(dnp no)
		(property "Reference" "#PWR0441"
			(at 180.34 170.18 0)
			(effects
				(font
					(size 1.27 1.27)
					(thickness 0.15)
				)
				(justify left bottom)
				(hide yes)
			)
		)
		(property "Value" "GND"
			(at 171.45 171.45 0)
			(effects
				(font
					(size 1.27 1.27)
					(thickness 0.15)
				)
			)
		)
		(property "Footprint" ""
			(at 180.34 175.26 0)
			(effects
				(font
					(size 1.27 1.27)
					(thickness 0.15)
				)
				(justify left bottom)
				(hide yes)
			)
		)
		(property "Datasheet" ""
			(at 180.34 180.34 0)
			(effects
				(font
					(size 1.27 1.27)
					(thickness 0.15)
				)
				(justify left bottom)
				(hide yes)
			)
		)
		(property "Description" ""
			(at 171.45 167.64 0)
			(effects
				(font
					(size 1.27 1.27)
				)
				(hide yes)
			)
		)
		(property "Author" "Antmicro"
			(at 180.34 175.26 0)
			(effects
				(font
					(size 1.27 1.27)
					(thickness 0.15)
				)
				(justify left bottom)
				(hide yes)
			)
		)
		(property "License" "Apache-2.0"
			(at 180.34 177.8 0)
			(effects
				(font
					(size 1.27 1.27)
					(thickness 0.15)
				)
				(justify left bottom)
				(hide yes)
			)
		)
		(pin "1"
		)
		(instances
			(project "com-express-7-baseboard"
				(path ""
					(reference "#PWR0441")
					(unit 1)
				)
			)
		)
	)
	(symbol
		(lib_id "antmicropower:+1V0")
		(at 179.07 48.26 0)
		(unit 1)
		(exclude_from_sim no)
		(in_bom yes)
		(on_board yes)
		(dnp no)
		(property "Reference" "#PWR0121"
			(at 179.07 52.07 0)
			(effects
				(font
					(size 1.27 1.27)
				)
				(hide yes)
			)
		)
		(property "Value" "+1V0"
			(at 179.07 44.45 0)
			(effects
				(font
					(size 1.27 1.27)
				)
			)
		)
		(property "Footprint" ""
			(at 179.07 48.26 0)
			(effects
				(font
					(size 1.27 1.27)
				)
				(hide yes)
			)
		)
		(property "Datasheet" ""
			(at 179.07 48.26 0)
			(effects
				(font
					(size 1.27 1.27)
				)
				(hide yes)
			)
		)
		(property "Description" ""
			(at 179.07 48.26 0)
			(effects
				(font
					(size 1.27 1.27)
				)
				(hide yes)
			)
		)
		(pin "1"
		)
		(instances
			(project "com-express-7-baseboard"
				(path ""
					(reference "#PWR0121")
					(unit 1)
				)
			)
		)
	)
	(symbol
		(lib_id "antmicroResistors0402:R_2k2_0402")
		(at 236.22 222.25 90)
		(unit 1)
		(exclude_from_sim no)
		(in_bom yes)
		(on_board yes)
		(dnp no)
		(property "Reference" "R325"
			(at 237.49 218.44 90)
			(effects
				(font
					(size 1.27 1.27)
					(thickness 0.15)
				)
				(justify right)
			)
		)
		(property "Value" "R_2k2_0402"
			(at 248.92 201.93 0)
			(effects
				(font
					(size 1.27 1.27)
					(thickness 0.15)
				)
				(justify left bottom)
				(hide yes)
			)
		)
		(property "Footprint" "antmicro-footprints:R_0402_1005Metric"
			(at 251.46 201.93 0)
			(effects
				(font
					(size 1.27 1.27)
					(thickness 0.15)
				)
				(justify left bottom)
				(hide yes)
			)
		)
		(property "Datasheet" "https://www.bourns.com/docs/product-datasheets/cr.pdf"
			(at 254 201.93 0)
			(effects
				(font
					(size 1.27 1.27)
					(thickness 0.15)
				)
				(justify left bottom)
				(hide yes)
			)
		)
		(property "Description" ""
			(at 236.22 222.25 0)
			(effects
				(font
					(size 1.27 1.27)
				)
				(hide yes)
			)
		)
		(property "MPN" "CR0402-FX-2201GLF"
			(at 256.54 201.93 0)
			(effects
				(font
					(size 1.27 1.27)
					(thickness 0.15)
				)
				(justify left bottom)
				(hide yes)
			)
		)
		(property "Manufacturer" "Bourns"
			(at 259.08 201.93 0)
			(effects
				(font
					(size 1.27 1.27)
					(thickness 0.15)
				)
				(justify left bottom)
				(hide yes)
			)
		)
		(property "License" "Apache-2.0"
			(at 261.62 201.93 0)
			(effects
				(font
					(size 1.27 1.27)
					(thickness 0.15)
				)
				(justify left bottom)
				(hide yes)
			)
		)
		(property "Author" "Antmicro"
			(at 264.16 201.93 0)
			(effects
				(font
					(size 1.27 1.27)
					(thickness 0.15)
				)
				(justify left bottom)
				(hide yes)
			)
		)
		(property "Val" "2k2"
			(at 237.49 220.98 90)
			(effects
				(font
					(size 1.27 1.27)
					(thickness 0.15)
				)
				(justify right)
			)
		)
		(property "Tolerance" "1%"
			(at 246.38 201.93 0)
			(effects
				(font
					(size 1.27 1.27)
				)
				(justify left bottom)
				(hide yes)
			)
		)
		(pin "1"
		)
		(pin "2"
		)
		(instances
			(project "com-express-7-baseboard"
				(path ""
					(reference "R325")
					(unit 1)
				)
			)
		)
	)
	(symbol
		(lib_id "antmicropower:GND")
		(at 67.31 52.07 0)
		(mirror y)
		(unit 1)
		(exclude_from_sim no)
		(in_bom yes)
		(on_board yes)
		(dnp no)
		(property "Reference" "#PWR092"
			(at 58.42 54.61 0)
			(effects
				(font
					(size 1.27 1.27)
					(thickness 0.15)
				)
				(justify left bottom)
				(hide yes)
			)
		)
		(property "Value" "GND"
			(at 67.31 55.88 0)
			(effects
				(font
					(size 1.27 1.27)
					(thickness 0.15)
				)
			)
		)
		(property "Footprint" ""
			(at 58.42 59.69 0)
			(effects
				(font
					(size 1.27 1.27)
					(thickness 0.15)
				)
				(justify left bottom)
				(hide yes)
			)
		)
		(property "Datasheet" ""
			(at 58.42 64.77 0)
			(effects
				(font
					(size 1.27 1.27)
					(thickness 0.15)
				)
				(justify left bottom)
				(hide yes)
			)
		)
		(property "Description" ""
			(at 67.31 52.07 0)
			(effects
				(font
					(size 1.27 1.27)
				)
				(hide yes)
			)
		)
		(property "Author" "Antmicro"
			(at 58.42 59.69 0)
			(effects
				(font
					(size 1.27 1.27)
					(thickness 0.15)
				)
				(justify left bottom)
				(hide yes)
			)
		)
		(property "License" "Apache-2.0"
			(at 58.42 62.23 0)
			(effects
				(font
					(size 1.27 1.27)
					(thickness 0.15)
				)
				(justify left bottom)
				(hide yes)
			)
		)
		(pin "1"
		)
		(instances
			(project "com-express-7-baseboard"
				(path ""
					(reference "#PWR092")
					(unit 1)
				)
			)
		)
	)
	(symbol
		(lib_id "antmicropower:GND")
		(at 254 274.32 0)
		(unit 1)
		(exclude_from_sim no)
		(in_bom yes)
		(on_board yes)
		(dnp no)
		(property "Reference" "#PWR0465"
			(at 262.89 276.86 0)
			(effects
				(font
					(size 1.27 1.27)
					(thickness 0.15)
				)
				(justify left bottom)
				(hide yes)
			)
		)
		(property "Value" "GND"
			(at 254 278.13 0)
			(effects
				(font
					(size 1.27 1.27)
					(thickness 0.15)
				)
			)
		)
		(property "Footprint" ""
			(at 262.89 281.94 0)
			(effects
				(font
					(size 1.27 1.27)
					(thickness 0.15)
				)
				(justify left bottom)
				(hide yes)
			)
		)
		(property "Datasheet" ""
			(at 262.89 287.02 0)
			(effects
				(font
					(size 1.27 1.27)
					(thickness 0.15)
				)
				(justify left bottom)
				(hide yes)
			)
		)
		(property "Description" ""
			(at 254 274.32 0)
			(effects
				(font
					(size 1.27 1.27)
				)
				(hide yes)
			)
		)
		(property "Author" "Antmicro"
			(at 262.89 281.94 0)
			(effects
				(font
					(size 1.27 1.27)
					(thickness 0.15)
				)
				(justify left bottom)
				(hide yes)
			)
		)
		(property "License" "Apache-2.0"
			(at 262.89 284.48 0)
			(effects
				(font
					(size 1.27 1.27)
					(thickness 0.15)
				)
				(justify left bottom)
				(hide yes)
			)
		)
		(pin "1"
		)
		(instances
			(project "com-express-7-baseboard"
				(path ""
					(reference "#PWR0465")
					(unit 1)
				)
			)
		)
	)
	(symbol
		(lib_id "antmicroCapacitors0603:C_22u_16V_0603")
		(at 77.47 52.07 90)
		(unit 1)
		(exclude_from_sim no)
		(in_bom yes)
		(on_board yes)
		(dnp no)
		(fields_autoplaced yes)
		(property "Reference" "C42"
			(at 80.01 46.9835 90)
			(effects
				(font
					(size 1.27 1.27)
					(thickness 0.15)
				)
				(justify right)
			)
		)
		(property "Value" "C_22u_16V_0603"
			(at 87.63 31.75 0)
			(effects
				(font
					(size 1.27 1.27)
					(thickness 0.15)
				)
				(justify left bottom)
				(hide yes)
			)
		)
		(property "Footprint" "antmicro-footprints:C_0603_1608Metric"
			(at 90.17 31.75 0)
			(effects
				(font
					(size 1.27 1.27)
					(thickness 0.15)
				)
				(justify left bottom)
				(hide yes)
			)
		)
		(property "Datasheet" "https://product.samsungsem.com/mlcc/CL10A226MO7JZN.do"
			(at 92.71 31.75 0)
			(effects
				(font
					(size 1.27 1.27)
					(thickness 0.15)
				)
				(justify left bottom)
				(hide yes)
			)
		)
		(property "Description" ""
			(at 77.47 52.07 0)
			(effects
				(font
					(size 1.27 1.27)
				)
				(hide yes)
			)
		)
		(property "MPN" "CL10A226MO7JZNC"
			(at 95.25 31.75 0)
			(effects
				(font
					(size 1.27 1.27)
					(thickness 0.15)
				)
				(justify left bottom)
				(hide yes)
			)
		)
		(property "Manufacturer" "Samsung Electro-Mechanics"
			(at 97.79 31.75 0)
			(effects
				(font
					(size 1.27 1.27)
					(thickness 0.15)
				)
				(justify left bottom)
				(hide yes)
			)
		)
		(property "License" "Apache-2.0"
			(at 100.33 31.75 0)
			(effects
				(font
					(size 1.27 1.27)
					(thickness 0.15)
				)
				(justify left bottom)
				(hide yes)
			)
		)
		(property "Author" "Antmicro"
			(at 102.87 31.75 0)
			(effects
				(font
					(size 1.27 1.27)
					(thickness 0.15)
				)
				(justify left bottom)
				(hide yes)
			)
		)
		(property "Val" "22u"
			(at 80.01 49.5235 90)
			(effects
				(font
					(size 1.27 1.27)
					(thickness 0.15)
				)
				(justify right)
			)
		)
		(property "Voltage" "16V"
			(at 80.01 52.0635 90)
			(effects
				(font
					(size 1.27 1.27)
				)
				(justify right)
				(hide yes)
			)
		)
		(property "Dielectric" ""
			(at 107.95 31.75 0)
			(effects
				(font
					(size 1.27 1.27)
				)
				(justify left bottom)
				(hide yes)
			)
		)
		(property "Public" "False"
			(at 110.49 31.75 0)
			(effects
				(font
					(size 1.27 1.27)
				)
				(justify left bottom)
				(hide yes)
			)
		)
		(pin "2"
		)
		(pin "1"
		)
		(instances
			(project "com-express-7-baseboard"
				(path ""
					(reference "C42")
					(unit 1)
				)
			)
		)
	)
	(symbol
		(lib_id "antmicroFixedInductors:L_1u8_6.8A_WE-MAPI-4020")
		(at 299.72 134.62 0)
		(unit 1)
		(exclude_from_sim no)
		(in_bom yes)
		(on_board yes)
		(dnp no)
		(fields_autoplaced yes)
		(property "Reference" "L4"
			(at 302.26 129.54 0)
			(effects
				(font
					(size 1.27 1.27)
					(thickness 0.15)
				)
			)
		)
		(property "Value" "L_1u8_6.8A_WE-MAPI-4020"
			(at 313.69 137.16 0)
			(effects
				(font
					(size 1.27 1.27)
					(thickness 0.15)
				)
				(justify left bottom)
				(hide yes)
			)
		)
		(property "Footprint" "antmicro-footprints:L_WE-MAPI-4020"
			(at 313.69 142.24 0)
			(effects
				(font
					(size 1.27 1.27)
					(thickness 0.15)
				)
				(justify left bottom)
				(hide yes)
			)
		)
		(property "Datasheet" "https://www.we-online.com/components/products/datasheet/74438356018.pdf"
			(at 313.69 144.78 0)
			(effects
				(font
					(size 1.27 1.27)
					(thickness 0.15)
				)
				(justify left bottom)
				(hide yes)
			)
		)
		(property "Description" ""
			(at 299.72 134.62 0)
			(effects
				(font
					(size 1.27 1.27)
				)
				(hide yes)
			)
		)
		(property "Val" "1u8/6.8A"
			(at 302.26 132.08 0)
			(effects
				(font
					(size 1.27 1.27)
					(thickness 0.15)
				)
			)
		)
		(property "Manufacturer" "Würth Elektronik"
			(at 313.69 147.32 0)
			(effects
				(font
					(size 1.27 1.27)
					(thickness 0.15)
				)
				(justify left bottom)
				(hide yes)
			)
		)
		(property "MPN" "74438356018"
			(at 313.69 149.86 0)
			(effects
				(font
					(size 1.27 1.27)
					(thickness 0.15)
				)
				(justify left bottom)
				(hide yes)
			)
		)
		(property "ISat" "6.5 A"
			(at 313.69 151.13 0)
			(effects
				(font
					(size 1.27 1.27)
				)
				(justify left)
				(hide yes)
			)
		)
		(property "IMax" "6.8 A"
			(at 313.69 154.94 0)
			(effects
				(font
					(size 1.27 1.27)
					(thickness 0.15)
				)
				(justify left bottom)
				(hide yes)
			)
		)
		(property "Size" "4.1x4.1mm"
			(at 313.69 157.48 0)
			(effects
				(font
					(size 1.27 1.27)
					(thickness 0.15)
				)
				(justify left bottom)
				(hide yes)
			)
		)
		(property "Author" "Antmicro"
			(at 313.69 160.02 0)
			(effects
				(font
					(size 1.27 1.27)
					(thickness 0.15)
				)
				(justify left bottom)
				(hide yes)
			)
		)
		(property "License" "Apache-2.0"
			(at 313.69 162.56 0)
			(effects
				(font
					(size 1.27 1.27)
					(thickness 0.15)
				)
				(justify left bottom)
				(hide yes)
			)
		)
		(property "Public" "False"
			(at 313.69 165.1 0)
			(effects
				(font
					(size 1.27 1.27)
				)
				(justify left bottom)
				(hide yes)
			)
		)
		(pin "1"
		)
		(pin "2"
		)
		(instances
			(project "com-express-7-baseboard"
				(path ""
					(reference "L4")
					(unit 1)
				)
			)
		)
	)
	(symbol
		(lib_id "antmicropower:+1V0")
		(at 254 243.84 0)
		(unit 1)
		(exclude_from_sim no)
		(in_bom yes)
		(on_board yes)
		(dnp no)
		(property "Reference" "#PWR0461"
			(at 254 247.65 0)
			(effects
				(font
					(size 1.27 1.27)
				)
				(hide yes)
			)
		)
		(property "Value" "+1V0"
			(at 254 240.03 0)
			(effects
				(font
					(size 1.27 1.27)
				)
			)
		)
		(property "Footprint" ""
			(at 254 243.84 0)
			(effects
				(font
					(size 1.27 1.27)
				)
				(hide yes)
			)
		)
		(property "Datasheet" ""
			(at 254 243.84 0)
			(effects
				(font
					(size 1.27 1.27)
				)
				(hide yes)
			)
		)
		(property "Description" ""
			(at 254 243.84 0)
			(effects
				(font
					(size 1.27 1.27)
				)
				(hide yes)
			)
		)
		(pin "1"
		)
		(instances
			(project "com-express-7-baseboard"
				(path ""
					(reference "#PWR0461")
					(unit 1)
				)
			)
		)
	)
	(symbol
		(lib_id "antmicropower:PWR_FLAG")
		(at 68.58 223.52 0)
		(unit 1)
		(exclude_from_sim no)
		(in_bom yes)
		(on_board yes)
		(dnp no)
		(property "Reference" "#FLG07"
			(at 68.58 221.615 0)
			(effects
				(font
					(size 1.27 1.27)
				)
				(hide yes)
			)
		)
		(property "Value" "PWR_FLAG"
			(at 68.58 219.71 0)
			(effects
				(font
					(size 1.27 1.27)
				)
			)
		)
		(property "Footprint" ""
			(at 68.58 223.52 0)
			(effects
				(font
					(size 1.27 1.27)
				)
				(hide yes)
			)
		)
		(property "Datasheet" ""
			(at 68.58 223.52 0)
			(effects
				(font
					(size 1.27 1.27)
				)
				(hide yes)
			)
		)
		(property "Description" ""
			(at 68.58 223.52 0)
			(effects
				(font
					(size 1.27 1.27)
				)
				(hide yes)
			)
		)
		(pin "1"
		)
		(instances
			(project "com-express-7-baseboard"
				(path ""
					(reference "#FLG07")
					(unit 1)
				)
			)
		)
	)
	(symbol
		(lib_id "antmicroCapacitors0603:C_22u_16V_0603")
		(at 257.81 138.43 90)
		(unit 1)
		(exclude_from_sim no)
		(in_bom yes)
		(on_board yes)
		(dnp no)
		(fields_autoplaced yes)
		(property "Reference" "C60"
			(at 260.35 133.3435 90)
			(effects
				(font
					(size 1.27 1.27)
					(thickness 0.15)
				)
				(justify right)
			)
		)
		(property "Value" "C_22u_16V_0603"
			(at 267.97 118.11 0)
			(effects
				(font
					(size 1.27 1.27)
					(thickness 0.15)
				)
				(justify left bottom)
				(hide yes)
			)
		)
		(property "Footprint" "antmicro-footprints:C_0603_1608Metric"
			(at 270.51 118.11 0)
			(effects
				(font
					(size 1.27 1.27)
					(thickness 0.15)
				)
				(justify left bottom)
				(hide yes)
			)
		)
		(property "Datasheet" "https://product.samsungsem.com/mlcc/CL10A226MO7JZN.do"
			(at 273.05 118.11 0)
			(effects
				(font
					(size 1.27 1.27)
					(thickness 0.15)
				)
				(justify left bottom)
				(hide yes)
			)
		)
		(property "Description" ""
			(at 257.81 138.43 0)
			(effects
				(font
					(size 1.27 1.27)
				)
				(hide yes)
			)
		)
		(property "MPN" "CL10A226MO7JZNC"
			(at 275.59 118.11 0)
			(effects
				(font
					(size 1.27 1.27)
					(thickness 0.15)
				)
				(justify left bottom)
				(hide yes)
			)
		)
		(property "Manufacturer" "Samsung Electro-Mechanics"
			(at 278.13 118.11 0)
			(effects
				(font
					(size 1.27 1.27)
					(thickness 0.15)
				)
				(justify left bottom)
				(hide yes)
			)
		)
		(property "License" "Apache-2.0"
			(at 280.67 118.11 0)
			(effects
				(font
					(size 1.27 1.27)
					(thickness 0.15)
				)
				(justify left bottom)
				(hide yes)
			)
		)
		(property "Author" "Antmicro"
			(at 283.21 118.11 0)
			(effects
				(font
					(size 1.27 1.27)
					(thickness 0.15)
				)
				(justify left bottom)
				(hide yes)
			)
		)
		(property "Val" "22u"
			(at 260.35 135.8835 90)
			(effects
				(font
					(size 1.27 1.27)
					(thickness 0.15)
				)
				(justify right)
			)
		)
		(property "Voltage" "16V"
			(at 260.35 138.4235 90)
			(effects
				(font
					(size 1.27 1.27)
				)
				(justify right)
				(hide yes)
			)
		)
		(property "Dielectric" ""
			(at 288.29 118.11 0)
			(effects
				(font
					(size 1.27 1.27)
				)
				(justify left bottom)
				(hide yes)
			)
		)
		(property "Public" "False"
			(at 290.83 118.11 0)
			(effects
				(font
					(size 1.27 1.27)
				)
				(justify left bottom)
				(hide yes)
			)
		)
		(pin "2"
		)
		(pin "1"
		)
		(instances
			(project "com-express-7-baseboard"
				(path ""
					(reference "C60")
					(unit 1)
				)
			)
		)
	)
	(symbol
		(lib_id "antmicropower:GND")
		(at 82.55 62.23 0)
		(mirror y)
		(unit 1)
		(exclude_from_sim no)
		(in_bom yes)
		(on_board yes)
		(dnp no)
		(property "Reference" "#PWR098"
			(at 73.66 64.77 0)
			(effects
				(font
					(size 1.27 1.27)
					(thickness 0.15)
				)
				(justify left bottom)
				(hide yes)
			)
		)
		(property "Value" "GND"
			(at 82.55 66.04 0)
			(effects
				(font
					(size 1.27 1.27)
					(thickness 0.15)
				)
			)
		)
		(property "Footprint" ""
			(at 73.66 69.85 0)
			(effects
				(font
					(size 1.27 1.27)
					(thickness 0.15)
				)
				(justify left bottom)
				(hide yes)
			)
		)
		(property "Datasheet" ""
			(at 73.66 74.93 0)
			(effects
				(font
					(size 1.27 1.27)
					(thickness 0.15)
				)
				(justify left bottom)
				(hide yes)
			)
		)
		(property "Description" ""
			(at 82.55 62.23 0)
			(effects
				(font
					(size 1.27 1.27)
				)
				(hide yes)
			)
		)
		(property "Author" "Antmicro"
			(at 73.66 69.85 0)
			(effects
				(font
					(size 1.27 1.27)
					(thickness 0.15)
				)
				(justify left bottom)
				(hide yes)
			)
		)
		(property "License" "Apache-2.0"
			(at 73.66 72.39 0)
			(effects
				(font
					(size 1.27 1.27)
					(thickness 0.15)
				)
				(justify left bottom)
				(hide yes)
			)
		)
		(pin "1"
		)
		(instances
			(project "com-express-7-baseboard"
				(path ""
					(reference "#PWR098")
					(unit 1)
				)
			)
		)
	)
	(symbol
		(lib_id "antmicroCapacitors0402:C_1u_0402")
		(at 300.99 66.04 90)
		(unit 1)
		(exclude_from_sim no)
		(in_bom yes)
		(on_board yes)
		(dnp no)
		(fields_autoplaced yes)
		(property "Reference" "C62"
			(at 303.53 62.2235 90)
			(effects
				(font
					(size 1.27 1.27)
					(thickness 0.15)
				)
				(justify right)
			)
		)
		(property "Value" "C_1u_0402"
			(at 311.15 45.72 0)
			(effects
				(font
					(size 1.27 1.27)
					(thickness 0.15)
				)
				(justify left bottom)
				(hide yes)
			)
		)
		(property "Footprint" "antmicro-footprints:C_0402_1005Metric"
			(at 313.69 45.72 0)
			(effects
				(font
					(size 1.27 1.27)
					(thickness 0.15)
				)
				(justify left bottom)
				(hide yes)
			)
		)
		(property "Datasheet" "https://product.tdk.com/en/search/capacitor/ceramic/mlcc/info?part_no=C1005X6S1A105K050BC"
			(at 316.23 45.72 0)
			(effects
				(font
					(size 1.27 1.27)
					(thickness 0.15)
				)
				(justify left bottom)
				(hide yes)
			)
		)
		(property "Description" ""
			(at 300.99 66.04 0)
			(effects
				(font
					(size 1.27 1.27)
				)
				(hide yes)
			)
		)
		(property "MPN" "C1005X6S1A105K050BC"
			(at 318.77 45.72 0)
			(effects
				(font
					(size 1.27 1.27)
					(thickness 0.15)
				)
				(justify left bottom)
				(hide yes)
			)
		)
		(property "Manufacturer" "TDK"
			(at 321.31 45.72 0)
			(effects
				(font
					(size 1.27 1.27)
					(thickness 0.15)
				)
				(justify left bottom)
				(hide yes)
			)
		)
		(property "License" "Apache-2.0"
			(at 323.85 45.72 0)
			(effects
				(font
					(size 1.27 1.27)
					(thickness 0.15)
				)
				(justify left bottom)
				(hide yes)
			)
		)
		(property "Author" "Antmicro"
			(at 326.39 45.72 0)
			(effects
				(font
					(size 1.27 1.27)
					(thickness 0.15)
				)
				(justify left bottom)
				(hide yes)
			)
		)
		(property "Val" "1u"
			(at 303.53 64.7635 90)
			(effects
				(font
					(size 1.27 1.27)
					(thickness 0.15)
				)
				(justify right)
			)
		)
		(property "Voltage" ""
			(at 328.93 45.72 0)
			(effects
				(font
					(size 1.27 1.27)
				)
				(justify left bottom)
				(hide yes)
			)
		)
		(property "Dielectric" ""
			(at 331.47 45.72 0)
			(effects
				(font
					(size 1.27 1.27)
				)
				(justify left bottom)
				(hide yes)
			)
		)
		(property "Public" "False"
			(at 334.01 45.72 0)
			(effects
				(font
					(size 1.27 1.27)
				)
				(justify left bottom)
				(hide yes)
			)
		)
		(pin "1"
		)
		(pin "2"
		)
		(instances
			(project "com-express-7-baseboard"
				(path ""
					(reference "C62")
					(unit 1)
				)
			)
		)
	)
	(symbol
		(lib_id "antmicroResistorsmisc:R_0R001_0805")
		(at 327.66 55.88 0)
		(unit 1)
		(exclude_from_sim no)
		(in_bom yes)
		(on_board yes)
		(dnp no)
		(property "Reference" "R113"
			(at 330.2 50.8 0)
			(effects
				(font
					(size 1.27 1.27)
					(thickness 0.15)
				)
			)
		)
		(property "Value" "R_0R001_0805"
			(at 347.98 68.58 0)
			(effects
				(font
					(size 1.27 1.27)
					(thickness 0.15)
				)
				(justify left bottom)
				(hide yes)
			)
		)
		(property "Footprint" "antmicro-footprints:R_0805_2012Metric"
			(at 347.98 71.12 0)
			(effects
				(font
					(size 1.27 1.27)
					(thickness 0.15)
				)
				(justify left bottom)
				(hide yes)
			)
		)
		(property "Datasheet" "https://www.eaton.com/content/dam/eaton/products/electronic-components/resources/data-sheet/eaton-msma-automotive-smd-current-sense-resistor-metal-strip-data-sheet-elx1179.pdf"
			(at 347.98 73.66 0)
			(effects
				(font
					(size 1.27 1.27)
					(thickness 0.15)
				)
				(justify left bottom)
				(hide yes)
			)
		)
		(property "Description" ""
			(at 327.66 55.88 0)
			(effects
				(font
					(size 1.27 1.27)
				)
				(hide yes)
			)
		)
		(property "MPN" "MSMA0805R0010FSM"
			(at 347.98 76.2 0)
			(effects
				(font
					(size 1.27 1.27)
					(thickness 0.15)
				)
				(justify left bottom)
				(hide yes)
			)
		)
		(property "Manufacturer" "Eaton"
			(at 347.98 78.74 0)
			(effects
				(font
					(size 1.27 1.27)
					(thickness 0.15)
				)
				(justify left bottom)
				(hide yes)
			)
		)
		(property "License" "Apache-2.0"
			(at 347.98 81.28 0)
			(effects
				(font
					(size 1.27 1.27)
					(thickness 0.15)
				)
				(justify left bottom)
				(hide yes)
			)
		)
		(property "Author" "Antmicro"
			(at 347.98 83.82 0)
			(effects
				(font
					(size 1.27 1.27)
					(thickness 0.15)
				)
				(justify left bottom)
				(hide yes)
			)
		)
		(property "Val" "0R001"
			(at 330.2 53.34 0)
			(effects
				(font
					(size 1.27 1.27)
					(thickness 0.15)
				)
			)
		)
		(property "Tolerance" "1%"
			(at 347.98 66.04 0)
			(effects
				(font
					(size 1.27 1.27)
				)
				(justify left bottom)
				(hide yes)
			)
		)
		(property "Public" "False"
			(at 347.98 86.36 0)
			(effects
				(font
					(size 1.27 1.27)
				)
				(justify left bottom)
				(hide yes)
			)
		)
		(pin "2"
		)
		(pin "1"
		)
		(instances
			(project "com-express-7-baseboard"
				(path ""
					(reference "R113")
					(unit 1)
				)
			)
		)
	)
	(symbol
		(lib_id "antmicropower:+3V3_AON")
		(at 388.62 218.44 0)
		(unit 1)
		(exclude_from_sim no)
		(in_bom yes)
		(on_board yes)
		(dnp no)
		(property "Reference" "#PWR0153"
			(at 388.62 222.25 0)
			(effects
				(font
					(size 1.27 1.27)
				)
				(hide yes)
			)
		)
		(property "Value" "+3V3_AON"
			(at 388.62 213.36 0)
			(effects
				(font
					(size 1.27 1.27)
				)
			)
		)
		(property "Footprint" ""
			(at 388.62 218.44 0)
			(effects
				(font
					(size 1.27 1.27)
				)
				(hide yes)
			)
		)
		(property "Datasheet" ""
			(at 388.62 218.44 0)
			(effects
				(font
					(size 1.27 1.27)
				)
				(hide yes)
			)
		)
		(property "Description" ""
			(at 388.62 218.44 0)
			(effects
				(font
					(size 1.27 1.27)
				)
				(hide yes)
			)
		)
		(pin "1"
		)
		(instances
			(project "com-express-7-baseboard"
				(path ""
					(reference "#PWR0153")
					(unit 1)
				)
			)
		)
	)
	(symbol
		(lib_id "antmicroCapacitors0603:C_22u_16V_0603")
		(at 237.49 59.69 90)
		(unit 1)
		(exclude_from_sim no)
		(in_bom yes)
		(on_board yes)
		(dnp no)
		(fields_autoplaced yes)
		(property "Reference" "C59"
			(at 240.03 54.6035 90)
			(effects
				(font
					(size 1.27 1.27)
					(thickness 0.15)
				)
				(justify right)
			)
		)
		(property "Value" "C_22u_16V_0603"
			(at 247.65 39.37 0)
			(effects
				(font
					(size 1.27 1.27)
					(thickness 0.15)
				)
				(justify left bottom)
				(hide yes)
			)
		)
		(property "Footprint" "antmicro-footprints:C_0603_1608Metric"
			(at 250.19 39.37 0)
			(effects
				(font
					(size 1.27 1.27)
					(thickness 0.15)
				)
				(justify left bottom)
				(hide yes)
			)
		)
		(property "Datasheet" "https://product.samsungsem.com/mlcc/CL10A226MO7JZN.do"
			(at 252.73 39.37 0)
			(effects
				(font
					(size 1.27 1.27)
					(thickness 0.15)
				)
				(justify left bottom)
				(hide yes)
			)
		)
		(property "Description" ""
			(at 237.49 59.69 0)
			(effects
				(font
					(size 1.27 1.27)
				)
				(hide yes)
			)
		)
		(property "MPN" "CL10A226MO7JZNC"
			(at 255.27 39.37 0)
			(effects
				(font
					(size 1.27 1.27)
					(thickness 0.15)
				)
				(justify left bottom)
				(hide yes)
			)
		)
		(property "Manufacturer" "Samsung Electro-Mechanics"
			(at 257.81 39.37 0)
			(effects
				(font
					(size 1.27 1.27)
					(thickness 0.15)
				)
				(justify left bottom)
				(hide yes)
			)
		)
		(property "License" "Apache-2.0"
			(at 260.35 39.37 0)
			(effects
				(font
					(size 1.27 1.27)
					(thickness 0.15)
				)
				(justify left bottom)
				(hide yes)
			)
		)
		(property "Author" "Antmicro"
			(at 262.89 39.37 0)
			(effects
				(font
					(size 1.27 1.27)
					(thickness 0.15)
				)
				(justify left bottom)
				(hide yes)
			)
		)
		(property "Val" "22u"
			(at 240.03 57.1435 90)
			(effects
				(font
					(size 1.27 1.27)
					(thickness 0.15)
				)
				(justify right)
			)
		)
		(property "Voltage" "16V"
			(at 240.03 59.6835 90)
			(effects
				(font
					(size 1.27 1.27)
				)
				(justify right)
				(hide yes)
			)
		)
		(property "Dielectric" ""
			(at 267.97 39.37 0)
			(effects
				(font
					(size 1.27 1.27)
				)
				(justify left bottom)
				(hide yes)
			)
		)
		(property "Public" "False"
			(at 270.51 39.37 0)
			(effects
				(font
					(size 1.27 1.27)
				)
				(justify left bottom)
				(hide yes)
			)
		)
		(pin "2"
		)
		(pin "1"
		)
		(instances
			(project "com-express-7-baseboard"
				(path ""
					(reference "C59")
					(unit 1)
				)
			)
		)
	)
	(symbol
		(lib_id "antmicropower:GND")
		(at 193.04 246.38 0)
		(mirror y)
		(unit 1)
		(exclude_from_sim no)
		(in_bom yes)
		(on_board yes)
		(dnp no)
		(property "Reference" "#PWR0125"
			(at 184.15 248.92 0)
			(effects
				(font
					(size 1.27 1.27)
					(thickness 0.15)
				)
				(justify left bottom)
				(hide yes)
			)
		)
		(property "Value" "GND"
			(at 193.04 250.19 0)
			(effects
				(font
					(size 1.27 1.27)
					(thickness 0.15)
				)
			)
		)
		(property "Footprint" ""
			(at 184.15 254 0)
			(effects
				(font
					(size 1.27 1.27)
					(thickness 0.15)
				)
				(justify left bottom)
				(hide yes)
			)
		)
		(property "Datasheet" ""
			(at 184.15 259.08 0)
			(effects
				(font
					(size 1.27 1.27)
					(thickness 0.15)
				)
				(justify left bottom)
				(hide yes)
			)
		)
		(property "Description" ""
			(at 193.04 246.38 0)
			(effects
				(font
					(size 1.27 1.27)
				)
				(hide yes)
			)
		)
		(property "Author" "Antmicro"
			(at 184.15 254 0)
			(effects
				(font
					(size 1.27 1.27)
					(thickness 0.15)
				)
				(justify left bottom)
				(hide yes)
			)
		)
		(property "License" "Apache-2.0"
			(at 184.15 256.54 0)
			(effects
				(font
					(size 1.27 1.27)
					(thickness 0.15)
				)
				(justify left bottom)
				(hide yes)
			)
		)
		(pin "1"
		)
		(instances
			(project "com-express-7-baseboard"
				(path ""
					(reference "#PWR0125")
					(unit 1)
				)
			)
		)
	)
	(symbol
		(lib_id "antmicroCapacitors0402:C_1u_0402")
		(at 401.32 66.04 90)
		(unit 1)
		(exclude_from_sim no)
		(in_bom yes)
		(on_board yes)
		(dnp no)
		(property "Reference" "C70"
			(at 403.86 62.2235 90)
			(effects
				(font
					(size 1.27 1.27)
					(thickness 0.15)
				)
				(justify right)
			)
		)
		(property "Value" "C_1u_0402"
			(at 411.48 45.72 0)
			(effects
				(font
					(size 1.27 1.27)
					(thickness 0.15)
				)
				(justify left bottom)
				(hide yes)
			)
		)
		(property "Footprint" "antmicro-footprints:C_0402_1005Metric"
			(at 414.02 45.72 0)
			(effects
				(font
					(size 1.27 1.27)
					(thickness 0.15)
				)
				(justify left bottom)
				(hide yes)
			)
		)
		(property "Datasheet" "https://product.tdk.com/en/search/capacitor/ceramic/mlcc/info?part_no=C1005X6S1A105K050BC"
			(at 416.56 45.72 0)
			(effects
				(font
					(size 1.27 1.27)
					(thickness 0.15)
				)
				(justify left bottom)
				(hide yes)
			)
		)
		(property "Description" ""
			(at 401.32 66.04 0)
			(effects
				(font
					(size 1.27 1.27)
				)
				(hide yes)
			)
		)
		(property "MPN" "C1005X6S1A105K050BC"
			(at 419.1 45.72 0)
			(effects
				(font
					(size 1.27 1.27)
					(thickness 0.15)
				)
				(justify left bottom)
				(hide yes)
			)
		)
		(property "Manufacturer" "TDK"
			(at 421.64 45.72 0)
			(effects
				(font
					(size 1.27 1.27)
					(thickness 0.15)
				)
				(justify left bottom)
				(hide yes)
			)
		)
		(property "License" "Apache-2.0"
			(at 424.18 45.72 0)
			(effects
				(font
					(size 1.27 1.27)
					(thickness 0.15)
				)
				(justify left bottom)
				(hide yes)
			)
		)
		(property "Author" "Antmicro"
			(at 426.72 45.72 0)
			(effects
				(font
					(size 1.27 1.27)
					(thickness 0.15)
				)
				(justify left bottom)
				(hide yes)
			)
		)
		(property "Val" "1u"
			(at 403.86 64.7635 90)
			(effects
				(font
					(size 1.27 1.27)
					(thickness 0.15)
				)
				(justify right)
			)
		)
		(property "Voltage" ""
			(at 429.26 45.72 0)
			(effects
				(font
					(size 1.27 1.27)
				)
				(justify left bottom)
				(hide yes)
			)
		)
		(property "Dielectric" ""
			(at 431.8 45.72 0)
			(effects
				(font
					(size 1.27 1.27)
				)
				(justify left bottom)
				(hide yes)
			)
		)
		(property "Public" "False"
			(at 434.34 45.72 0)
			(effects
				(font
					(size 1.27 1.27)
				)
				(justify left bottom)
				(hide yes)
			)
		)
		(pin "1"
		)
		(pin "2"
		)
		(instances
			(project "com-express-7-baseboard"
				(path ""
					(reference "C70")
					(unit 1)
				)
			)
		)
	)
	(symbol
		(lib_id "antmicroCapacitors0402:C_1u_0402")
		(at 149.86 59.69 90)
		(unit 1)
		(exclude_from_sim no)
		(in_bom yes)
		(on_board yes)
		(dnp no)
		(fields_autoplaced yes)
		(property "Reference" "C49"
			(at 152.4 55.8735 90)
			(effects
				(font
					(size 1.27 1.27)
					(thickness 0.15)
				)
				(justify right)
			)
		)
		(property "Value" "C_1u_0402"
			(at 160.02 39.37 0)
			(effects
				(font
					(size 1.27 1.27)
					(thickness 0.15)
				)
				(justify left bottom)
				(hide yes)
			)
		)
		(property "Footprint" "antmicro-footprints:C_0402_1005Metric"
			(at 162.56 39.37 0)
			(effects
				(font
					(size 1.27 1.27)
					(thickness 0.15)
				)
				(justify left bottom)
				(hide yes)
			)
		)
		(property "Datasheet" "https://product.tdk.com/en/search/capacitor/ceramic/mlcc/info?part_no=C1005X6S1A105K050BC"
			(at 165.1 39.37 0)
			(effects
				(font
					(size 1.27 1.27)
					(thickness 0.15)
				)
				(justify left bottom)
				(hide yes)
			)
		)
		(property "Description" ""
			(at 149.86 59.69 0)
			(effects
				(font
					(size 1.27 1.27)
				)
				(hide yes)
			)
		)
		(property "MPN" "C1005X6S1A105K050BC"
			(at 167.64 39.37 0)
			(effects
				(font
					(size 1.27 1.27)
					(thickness 0.15)
				)
				(justify left bottom)
				(hide yes)
			)
		)
		(property "Manufacturer" "TDK"
			(at 170.18 39.37 0)
			(effects
				(font
					(size 1.27 1.27)
					(thickness 0.15)
				)
				(justify left bottom)
				(hide yes)
			)
		)
		(property "License" "Apache-2.0"
			(at 172.72 39.37 0)
			(effects
				(font
					(size 1.27 1.27)
					(thickness 0.15)
				)
				(justify left bottom)
				(hide yes)
			)
		)
		(property "Author" "Antmicro"
			(at 175.26 39.37 0)
			(effects
				(font
					(size 1.27 1.27)
					(thickness 0.15)
				)
				(justify left bottom)
				(hide yes)
			)
		)
		(property "Val" "1u"
			(at 152.4 58.4135 90)
			(effects
				(font
					(size 1.27 1.27)
					(thickness 0.15)
				)
				(justify right)
			)
		)
		(property "Voltage" ""
			(at 177.8 39.37 0)
			(effects
				(font
					(size 1.27 1.27)
				)
				(justify left bottom)
				(hide yes)
			)
		)
		(property "Dielectric" ""
			(at 180.34 39.37 0)
			(effects
				(font
					(size 1.27 1.27)
				)
				(justify left bottom)
				(hide yes)
			)
		)
		(property "Public" "False"
			(at 182.88 39.37 0)
			(effects
				(font
					(size 1.27 1.27)
				)
				(justify left bottom)
				(hide yes)
			)
		)
		(pin "1"
		)
		(pin "2"
		)
		(instances
			(project "com-express-7-baseboard"
				(path ""
					(reference "C49")
					(unit 1)
				)
			)
		)
	)
	(symbol
		(lib_id "antmicroResistors0402:R_0R_0402")
		(at 93.98 49.53 0)
		(unit 1)
		(exclude_from_sim no)
		(in_bom yes)
		(on_board yes)
		(dnp no)
		(property "Reference" "R93"
			(at 101.6 48.26 0)
			(effects
				(font
					(size 1.27 1.27)
					(thickness 0.15)
				)
			)
		)
		(property "Value" "R_0R_0402"
			(at 114.3 62.23 0)
			(effects
				(font
					(size 1.27 1.27)
					(thickness 0.15)
				)
				(justify left bottom)
				(hide yes)
			)
		)
		(property "Footprint" "antmicro-footprints:R_0402_1005Metric"
			(at 114.3 64.77 0)
			(effects
				(font
					(size 1.27 1.27)
					(thickness 0.15)
				)
				(justify left bottom)
				(hide yes)
			)
		)
		(property "Datasheet" "https://industrial.panasonic.com/cdbs/www-data/pdf/RDA0000/AOA0000C301.pdf"
			(at 114.3 67.31 0)
			(effects
				(font
					(size 1.27 1.27)
					(thickness 0.15)
				)
				(justify left bottom)
				(hide yes)
			)
		)
		(property "Description" ""
			(at 93.98 49.53 0)
			(effects
				(font
					(size 1.27 1.27)
				)
				(hide yes)
			)
		)
		(property "MPN" "ERJ2GE0R00X"
			(at 114.3 69.85 0)
			(effects
				(font
					(size 1.27 1.27)
					(thickness 0.15)
				)
				(justify left bottom)
				(hide yes)
			)
		)
		(property "Manufacturer" "Panasonic"
			(at 114.3 72.39 0)
			(effects
				(font
					(size 1.27 1.27)
					(thickness 0.15)
				)
				(justify left bottom)
				(hide yes)
			)
		)
		(property "License" "Apache-2.0"
			(at 114.3 74.93 0)
			(effects
				(font
					(size 1.27 1.27)
					(thickness 0.15)
				)
				(justify left bottom)
				(hide yes)
			)
		)
		(property "Author" "Antmicro"
			(at 114.3 77.47 0)
			(effects
				(font
					(size 1.27 1.27)
					(thickness 0.15)
				)
				(justify left bottom)
				(hide yes)
			)
		)
		(property "Val" "0R"
			(at 100.33 50.8 0)
			(effects
				(font
					(size 1.27 1.27)
					(thickness 0.15)
				)
			)
		)
		(property "Tolerance" "~"
			(at 114.3 59.69 0)
			(effects
				(font
					(size 1.27 1.27)
				)
				(justify left bottom)
				(hide yes)
			)
		)
		(property "Current" "1A"
			(at 114.3 80.01 0)
			(effects
				(font
					(size 1.27 1.27)
					(thickness 0.15)
				)
				(justify left bottom)
				(hide yes)
			)
		)
		(property "Public" "False"
			(at 114.3 80.01 0)
			(effects
				(font
					(size 1.27 1.27)
				)
				(justify left bottom)
				(hide yes)
			)
		)
		(pin "1"
		)
		(pin "2"
		)
		(instances
			(project "com-express-7-baseboard"
				(path ""
					(reference "R93")
					(unit 1)
				)
			)
		)
	)
	(symbol
		(lib_id "antmicropower:+12V")
		(at 236.22 196.85 0)
		(unit 1)
		(exclude_from_sim no)
		(in_bom yes)
		(on_board yes)
		(dnp no)
		(property "Reference" "#PWR0464"
			(at 236.22 200.66 0)
			(effects
				(font
					(size 1.27 1.27)
				)
				(hide yes)
			)
		)
		(property "Value" "+12V"
			(at 236.22 193.04 0)
			(effects
				(font
					(size 1.27 1.27)
				)
			)
		)
		(property "Footprint" ""
			(at 236.22 196.85 0)
			(effects
				(font
					(size 1.27 1.27)
				)
				(hide yes)
			)
		)
		(property "Datasheet" ""
			(at 236.22 196.85 0)
			(effects
				(font
					(size 1.27 1.27)
				)
				(hide yes)
			)
		)
		(property "Description" ""
			(at 236.22 196.85 0)
			(effects
				(font
					(size 1.27 1.27)
				)
				(hide yes)
			)
		)
		(pin "1"
		)
		(instances
			(project "com-express-7-baseboard"
				(path ""
					(reference "#PWR0464")
					(unit 1)
				)
			)
		)
	)
	(symbol
		(lib_id "antmicroResistors0402:R_15k_0402")
		(at 139.7 63.5 90)
		(unit 1)
		(exclude_from_sim no)
		(in_bom yes)
		(on_board yes)
		(dnp no)
		(fields_autoplaced yes)
		(property "Reference" "R98"
			(at 142.24 59.6899 90)
			(effects
				(font
					(size 1.27 1.27)
					(thickness 0.15)
				)
				(justify right)
			)
		)
		(property "Value" "R_15k_0402"
			(at 152.4 43.18 0)
			(effects
				(font
					(size 1.27 1.27)
					(thickness 0.15)
				)
				(justify left bottom)
				(hide yes)
			)
		)
		(property "Footprint" "antmicro-footprints:R_0402_1005Metric"
			(at 154.94 43.18 0)
			(effects
				(font
					(size 1.27 1.27)
					(thickness 0.15)
				)
				(justify left bottom)
				(hide yes)
			)
		)
		(property "Datasheet" "https://www.bourns.com/docs/product-datasheets/cr.pdf"
			(at 157.48 43.18 0)
			(effects
				(font
					(size 1.27 1.27)
					(thickness 0.15)
				)
				(justify left bottom)
				(hide yes)
			)
		)
		(property "Description" ""
			(at 139.7 63.5 0)
			(effects
				(font
					(size 1.27 1.27)
				)
				(hide yes)
			)
		)
		(property "MPN" "CR0402-FX-1502GLF"
			(at 160.02 43.18 0)
			(effects
				(font
					(size 1.27 1.27)
					(thickness 0.15)
				)
				(justify left bottom)
				(hide yes)
			)
		)
		(property "Manufacturer" "Bourns"
			(at 162.56 43.18 0)
			(effects
				(font
					(size 1.27 1.27)
					(thickness 0.15)
				)
				(justify left bottom)
				(hide yes)
			)
		)
		(property "License" "Apache-2.0"
			(at 165.1 43.18 0)
			(effects
				(font
					(size 1.27 1.27)
					(thickness 0.15)
				)
				(justify left bottom)
				(hide yes)
			)
		)
		(property "Author" "Antmicro"
			(at 167.64 43.18 0)
			(effects
				(font
					(size 1.27 1.27)
					(thickness 0.15)
				)
				(justify left bottom)
				(hide yes)
			)
		)
		(property "Val" "15k"
			(at 142.24 62.2299 90)
			(effects
				(font
					(size 1.27 1.27)
					(thickness 0.15)
				)
				(justify right)
			)
		)
		(property "Tolerance" "1%"
			(at 149.86 43.18 0)
			(effects
				(font
					(size 1.27 1.27)
				)
				(justify left bottom)
				(hide yes)
			)
		)
		(property "Public" "False"
			(at 170.18 43.18 0)
			(effects
				(font
					(size 1.27 1.27)
				)
				(justify left bottom)
				(hide yes)
			)
		)
		(pin "2"
		)
		(pin "1"
		)
		(instances
			(project "com-express-7-baseboard"
				(path ""
					(reference "R98")
					(unit 1)
				)
			)
		)
	)
	(symbol
		(lib_id "antmicroTestPoints:TP_0.75mm_SMD")
		(at 257.81 199.39 0)
		(mirror x)
		(unit 1)
		(exclude_from_sim no)
		(in_bom no)
		(on_board yes)
		(dnp no)
		(property "Reference" "TP101"
			(at 261.62 199.39 0)
			(effects
				(font
					(size 1.27 1.27)
					(thickness 0.15)
				)
				(justify left)
			)
		)
		(property "Value" "TP_0.75mm_SMD"
			(at 268.605 195.58 0)
			(effects
				(font
					(size 1.27 1.27)
					(thickness 0.15)
				)
				(justify left bottom)
				(hide yes)
			)
		)
		(property "Footprint" "antmicro-footprints:TP_SMD_0.75mm"
			(at 268.605 193.04 0)
			(effects
				(font
					(size 1.27 1.27)
					(thickness 0.15)
				)
				(justify left bottom)
				(hide yes)
			)
		)
		(property "Datasheet" ""
			(at 275.59 186.69 0)
			(effects
				(font
					(size 1.27 1.27)
					(thickness 0.15)
				)
				(justify left bottom)
				(hide yes)
			)
		)
		(property "Description" ""
			(at 257.81 199.39 0)
			(effects
				(font
					(size 1.27 1.27)
				)
				(hide yes)
			)
		)
		(property "MPN" ""
			(at 268.605 187.96 0)
			(effects
				(font
					(size 1.27 1.27)
					(thickness 0.15)
				)
				(justify left bottom)
				(hide yes)
			)
		)
		(property "Manufacturer" ""
			(at 268.605 193.04 0)
			(effects
				(font
					(size 1.27 1.27)
					(thickness 0.15)
				)
				(justify left bottom)
				(hide yes)
			)
		)
		(property "Author" "Antmicro"
			(at 268.605 190.5 0)
			(effects
				(font
					(size 1.27 1.27)
					(thickness 0.15)
				)
				(justify left bottom)
				(hide yes)
			)
		)
		(property "License" "Apache-2.0"
			(at 268.605 187.96 0)
			(effects
				(font
					(size 1.27 1.27)
					(thickness 0.15)
				)
				(justify left bottom)
				(hide yes)
			)
		)
		(property "Public" "False"
			(at 267.97 185.42 0)
			(effects
				(font
					(size 1.27 1.27)
				)
				(justify left bottom)
				(hide yes)
			)
		)
		(pin "1"
		)
		(instances
			(project "com-express-7-baseboard"
				(path ""
					(reference "TP101")
					(unit 1)
				)
			)
		)
	)
	(symbol
		(lib_id "antmicropower:GND")
		(at 99.06 252.73 0)
		(unit 1)
		(exclude_from_sim no)
		(in_bom yes)
		(on_board yes)
		(dnp no)
		(property "Reference" "#PWR0104"
			(at 107.95 255.27 0)
			(effects
				(font
					(size 1.27 1.27)
					(thickness 0.15)
				)
				(justify left bottom)
				(hide yes)
			)
		)
		(property "Value" "GND"
			(at 99.06 256.54 0)
			(effects
				(font
					(size 1.27 1.27)
					(thickness 0.15)
				)
			)
		)
		(property "Footprint" ""
			(at 107.95 260.35 0)
			(effects
				(font
					(size 1.27 1.27)
					(thickness 0.15)
				)
				(justify left bottom)
				(hide yes)
			)
		)
		(property "Datasheet" ""
			(at 107.95 265.43 0)
			(effects
				(font
					(size 1.27 1.27)
					(thickness 0.15)
				)
				(justify left bottom)
				(hide yes)
			)
		)
		(property "Description" ""
			(at 99.06 252.73 0)
			(effects
				(font
					(size 1.27 1.27)
				)
				(hide yes)
			)
		)
		(property "Author" "Antmicro"
			(at 107.95 260.35 0)
			(effects
				(font
					(size 1.27 1.27)
					(thickness 0.15)
				)
				(justify left bottom)
				(hide yes)
			)
		)
		(property "License" "Apache-2.0"
			(at 107.95 262.89 0)
			(effects
				(font
					(size 1.27 1.27)
					(thickness 0.15)
				)
				(justify left bottom)
				(hide yes)
			)
		)
		(pin "1"
		)
		(instances
			(project "com-express-7-baseboard"
				(path ""
					(reference "#PWR0104")
					(unit 1)
				)
			)
		)
	)
	(symbol
		(lib_id "antmicropower:GND")
		(at 199.39 143.51 0)
		(unit 1)
		(exclude_from_sim no)
		(in_bom yes)
		(on_board yes)
		(dnp no)
		(property "Reference" "#PWR0124"
			(at 208.28 146.05 0)
			(effects
				(font
					(size 1.27 1.27)
					(thickness 0.15)
				)
				(justify left bottom)
				(hide yes)
			)
		)
		(property "Value" "GND"
			(at 199.39 147.32 0)
			(effects
				(font
					(size 1.27 1.27)
					(thickness 0.15)
				)
			)
		)
		(property "Footprint" ""
			(at 208.28 151.13 0)
			(effects
				(font
					(size 1.27 1.27)
					(thickness 0.15)
				)
				(justify left bottom)
				(hide yes)
			)
		)
		(property "Datasheet" ""
			(at 208.28 156.21 0)
			(effects
				(font
					(size 1.27 1.27)
					(thickness 0.15)
				)
				(justify left bottom)
				(hide yes)
			)
		)
		(property "Description" ""
			(at 199.39 143.51 0)
			(effects
				(font
					(size 1.27 1.27)
				)
				(hide yes)
			)
		)
		(property "Author" "Antmicro"
			(at 208.28 151.13 0)
			(effects
				(font
					(size 1.27 1.27)
					(thickness 0.15)
				)
				(justify left bottom)
				(hide yes)
			)
		)
		(property "License" "Apache-2.0"
			(at 208.28 153.67 0)
			(effects
				(font
					(size 1.27 1.27)
					(thickness 0.15)
				)
				(justify left bottom)
				(hide yes)
			)
		)
		(pin "1"
		)
		(instances
			(project "com-express-7-baseboard"
				(path ""
					(reference "#PWR0124")
					(unit 1)
				)
			)
		)
	)
	(symbol
		(lib_id "antmicroResistors0402:R_0R_0402")
		(at 158.75 242.57 0)
		(unit 1)
		(exclude_from_sim no)
		(in_bom yes)
		(on_board yes)
		(dnp no)
		(property "Reference" "R102"
			(at 156.21 241.3 0)
			(effects
				(font
					(size 1.27 1.27)
					(thickness 0.15)
				)
			)
		)
		(property "Value" "R_0R_0402"
			(at 179.07 255.27 0)
			(effects
				(font
					(size 1.27 1.27)
					(thickness 0.15)
				)
				(justify left bottom)
				(hide yes)
			)
		)
		(property "Footprint" "antmicro-footprints:R_0402_1005Metric"
			(at 179.07 257.81 0)
			(effects
				(font
					(size 1.27 1.27)
					(thickness 0.15)
				)
				(justify left bottom)
				(hide yes)
			)
		)
		(property "Datasheet" "https://industrial.panasonic.com/cdbs/www-data/pdf/RDA0000/AOA0000C301.pdf"
			(at 179.07 260.35 0)
			(effects
				(font
					(size 1.27 1.27)
					(thickness 0.15)
				)
				(justify left bottom)
				(hide yes)
			)
		)
		(property "Description" ""
			(at 158.75 242.57 0)
			(effects
				(font
					(size 1.27 1.27)
				)
				(hide yes)
			)
		)
		(property "MPN" "ERJ2GE0R00X"
			(at 179.07 262.89 0)
			(effects
				(font
					(size 1.27 1.27)
					(thickness 0.15)
				)
				(justify left bottom)
				(hide yes)
			)
		)
		(property "Manufacturer" "Panasonic"
			(at 179.07 265.43 0)
			(effects
				(font
					(size 1.27 1.27)
					(thickness 0.15)
				)
				(justify left bottom)
				(hide yes)
			)
		)
		(property "License" "Apache-2.0"
			(at 179.07 267.97 0)
			(effects
				(font
					(size 1.27 1.27)
					(thickness 0.15)
				)
				(justify left bottom)
				(hide yes)
			)
		)
		(property "Author" "Antmicro"
			(at 179.07 270.51 0)
			(effects
				(font
					(size 1.27 1.27)
					(thickness 0.15)
				)
				(justify left bottom)
				(hide yes)
			)
		)
		(property "Val" "0R"
			(at 165.1 241.3 0)
			(effects
				(font
					(size 1.27 1.27)
					(thickness 0.15)
				)
			)
		)
		(property "Tolerance" "~"
			(at 179.07 252.73 0)
			(effects
				(font
					(size 1.27 1.27)
				)
				(justify left bottom)
				(hide yes)
			)
		)
		(property "Current" "1A"
			(at 179.07 273.05 0)
			(effects
				(font
					(size 1.27 1.27)
					(thickness 0.15)
				)
				(justify left bottom)
				(hide yes)
			)
		)
		(property "Public" "False"
			(at 179.07 273.05 0)
			(effects
				(font
					(size 1.27 1.27)
				)
				(justify left bottom)
				(hide yes)
			)
		)
		(pin "2"
		)
		(pin "1"
		)
		(instances
			(project "com-express-7-baseboard"
				(path ""
					(reference "R102")
					(unit 1)
				)
			)
		)
	)
	(symbol
		(lib_id "antmicropower:GND")
		(at 170.18 254 0)
		(mirror y)
		(unit 1)
		(exclude_from_sim no)
		(in_bom yes)
		(on_board yes)
		(dnp no)
		(property "Reference" "#PWR0120"
			(at 161.29 256.54 0)
			(effects
				(font
					(size 1.27 1.27)
					(thickness 0.15)
				)
				(justify left bottom)
				(hide yes)
			)
		)
		(property "Value" "GND"
			(at 170.18 257.81 0)
			(effects
				(font
					(size 1.27 1.27)
					(thickness 0.15)
				)
			)
		)
		(property "Footprint" ""
			(at 161.29 261.62 0)
			(effects
				(font
					(size 1.27 1.27)
					(thickness 0.15)
				)
				(justify left bottom)
				(hide yes)
			)
		)
		(property "Datasheet" ""
			(at 161.29 266.7 0)
			(effects
				(font
					(size 1.27 1.27)
					(thickness 0.15)
				)
				(justify left bottom)
				(hide yes)
			)
		)
		(property "Description" ""
			(at 170.18 254 0)
			(effects
				(font
					(size 1.27 1.27)
				)
				(hide yes)
			)
		)
		(property "Author" "Antmicro"
			(at 161.29 261.62 0)
			(effects
				(font
					(size 1.27 1.27)
					(thickness 0.15)
				)
				(justify left bottom)
				(hide yes)
			)
		)
		(property "License" "Apache-2.0"
			(at 161.29 264.16 0)
			(effects
				(font
					(size 1.27 1.27)
					(thickness 0.15)
				)
				(justify left bottom)
				(hide yes)
			)
		)
		(pin "1"
		)
		(instances
			(project "com-express-7-baseboard"
				(path ""
					(reference "#PWR0120")
					(unit 1)
				)
			)
		)
	)
	(symbol
		(lib_id "antmicropower:GND")
		(at 257.81 140.97 0)
		(unit 1)
		(exclude_from_sim no)
		(in_bom yes)
		(on_board yes)
		(dnp no)
		(property "Reference" "#PWR0131"
			(at 266.7 143.51 0)
			(effects
				(font
					(size 1.27 1.27)
					(thickness 0.15)
				)
				(justify left bottom)
				(hide yes)
			)
		)
		(property "Value" "GND"
			(at 257.81 144.78 0)
			(effects
				(font
					(size 1.27 1.27)
					(thickness 0.15)
				)
			)
		)
		(property "Footprint" ""
			(at 266.7 148.59 0)
			(effects
				(font
					(size 1.27 1.27)
					(thickness 0.15)
				)
				(justify left bottom)
				(hide yes)
			)
		)
		(property "Datasheet" ""
			(at 266.7 153.67 0)
			(effects
				(font
					(size 1.27 1.27)
					(thickness 0.15)
				)
				(justify left bottom)
				(hide yes)
			)
		)
		(property "Description" ""
			(at 257.81 140.97 0)
			(effects
				(font
					(size 1.27 1.27)
				)
				(hide yes)
			)
		)
		(property "Author" "Antmicro"
			(at 266.7 148.59 0)
			(effects
				(font
					(size 1.27 1.27)
					(thickness 0.15)
				)
				(justify left bottom)
				(hide yes)
			)
		)
		(property "License" "Apache-2.0"
			(at 266.7 151.13 0)
			(effects
				(font
					(size 1.27 1.27)
					(thickness 0.15)
				)
				(justify left bottom)
				(hide yes)
			)
		)
		(pin "1"
		)
		(instances
			(project "com-express-7-baseboard"
				(path ""
					(reference "#PWR0131")
					(unit 1)
				)
			)
		)
	)
	(symbol
		(lib_id "antmicropower:GND")
		(at 160.02 143.51 0)
		(unit 1)
		(exclude_from_sim no)
		(in_bom yes)
		(on_board yes)
		(dnp no)
		(property "Reference" "#PWR0116"
			(at 168.91 146.05 0)
			(effects
				(font
					(size 1.27 1.27)
					(thickness 0.15)
				)
				(justify left bottom)
				(hide yes)
			)
		)
		(property "Value" "GND"
			(at 160.02 147.32 0)
			(effects
				(font
					(size 1.27 1.27)
					(thickness 0.15)
				)
			)
		)
		(property "Footprint" ""
			(at 168.91 151.13 0)
			(effects
				(font
					(size 1.27 1.27)
					(thickness 0.15)
				)
				(justify left bottom)
				(hide yes)
			)
		)
		(property "Datasheet" ""
			(at 168.91 156.21 0)
			(effects
				(font
					(size 1.27 1.27)
					(thickness 0.15)
				)
				(justify left bottom)
				(hide yes)
			)
		)
		(property "Description" ""
			(at 160.02 143.51 0)
			(effects
				(font
					(size 1.27 1.27)
				)
				(hide yes)
			)
		)
		(property "Author" "Antmicro"
			(at 168.91 151.13 0)
			(effects
				(font
					(size 1.27 1.27)
					(thickness 0.15)
				)
				(justify left bottom)
				(hide yes)
			)
		)
		(property "License" "Apache-2.0"
			(at 168.91 153.67 0)
			(effects
				(font
					(size 1.27 1.27)
					(thickness 0.15)
				)
				(justify left bottom)
				(hide yes)
			)
		)
		(pin "1"
		)
		(instances
			(project "com-express-7-baseboard"
				(path ""
					(reference "#PWR0116")
					(unit 1)
				)
			)
		)
	)
	(symbol
		(lib_id "antmicropower:GND")
		(at 179.07 63.5 0)
		(unit 1)
		(exclude_from_sim no)
		(in_bom yes)
		(on_board yes)
		(dnp no)
		(property "Reference" "#PWR0122"
			(at 187.96 66.04 0)
			(effects
				(font
					(size 1.27 1.27)
					(thickness 0.15)
				)
				(justify left bottom)
				(hide yes)
			)
		)
		(property "Value" "GND"
			(at 179.07 67.31 0)
			(effects
				(font
					(size 1.27 1.27)
					(thickness 0.15)
				)
			)
		)
		(property "Footprint" ""
			(at 187.96 71.12 0)
			(effects
				(font
					(size 1.27 1.27)
					(thickness 0.15)
				)
				(justify left bottom)
				(hide yes)
			)
		)
		(property "Datasheet" ""
			(at 187.96 76.2 0)
			(effects
				(font
					(size 1.27 1.27)
					(thickness 0.15)
				)
				(justify left bottom)
				(hide yes)
			)
		)
		(property "Description" ""
			(at 179.07 63.5 0)
			(effects
				(font
					(size 1.27 1.27)
				)
				(hide yes)
			)
		)
		(property "Author" "Antmicro"
			(at 187.96 71.12 0)
			(effects
				(font
					(size 1.27 1.27)
					(thickness 0.15)
				)
				(justify left bottom)
				(hide yes)
			)
		)
		(property "License" "Apache-2.0"
			(at 187.96 73.66 0)
			(effects
				(font
					(size 1.27 1.27)
					(thickness 0.15)
				)
				(justify left bottom)
				(hide yes)
			)
		)
		(pin "1"
		)
		(instances
			(project "com-express-7-baseboard"
				(path ""
					(reference "#PWR0122")
					(unit 1)
				)
			)
		)
	)
	(symbol
		(lib_id "antmicroPowerMeasurement:INA219AIDCNR")
		(at 53.34 237.49 0)
		(unit 1)
		(exclude_from_sim no)
		(in_bom yes)
		(on_board yes)
		(dnp no)
		(property "Reference" "U48"
			(at 60.96 232.41 0)
			(effects
				(font
					(size 1.27 1.27)
				)
			)
		)
		(property "Value" "INA219AIDCNR"
			(at 53.34 237.49 0)
			(effects
				(font
					(size 1.27 1.27)
				)
				(hide yes)
			)
		)
		(property "Footprint" "antmicro-footprints:SOT-23-8"
			(at 53.34 237.49 0)
			(effects
				(font
					(size 1.27 1.27)
				)
				(hide yes)
			)
		)
		(property "Datasheet" "https://www.ti.com/lit/ds/symlink/ina219.pdf?ts=1713856455637&ref_url=https%253A%252F%252Fwww.mouser.es%252F"
			(at 53.34 237.49 0)
			(effects
				(font
					(size 1.27 1.27)
				)
				(hide yes)
			)
		)
		(property "Description" ""
			(at 53.34 237.49 0)
			(effects
				(font
					(size 1.27 1.27)
				)
				(hide yes)
			)
		)
		(property "Manufacturer" "Texas Instruments"
			(at 53.34 237.49 0)
			(effects
				(font
					(size 1.27 1.27)
				)
				(hide yes)
			)
		)
		(property "MPN" "INA219AIDCNR"
			(at 60.96 234.95 0)
			(effects
				(font
					(size 1.27 1.27)
				)
			)
		)
		(property "Author" "Antmicro"
			(at 78.74 257.81 0)
			(effects
				(font
					(size 1.27 1.27)
					(thickness 0.15)
				)
				(justify left bottom)
				(hide yes)
			)
		)
		(property "License" "Apache-2.0"
			(at 78.74 260.35 0)
			(effects
				(font
					(size 1.27 1.27)
					(thickness 0.15)
				)
				(justify left bottom)
				(hide yes)
			)
		)
		(pin "1"
		)
		(pin "2"
		)
		(pin "5"
		)
		(pin "6"
		)
		(pin "8"
		)
		(pin "3"
		)
		(pin "7"
		)
		(pin "4"
		)
		(instances
			(project "com-express-7-baseboard"
				(path ""
					(reference "U48")
					(unit 1)
				)
			)
		)
	)
	(symbol
		(lib_id "antmicroResistors0402:R_110k_0402")
		(at 290.83 62.23 90)
		(unit 1)
		(exclude_from_sim no)
		(in_bom yes)
		(on_board yes)
		(dnp no)
		(fields_autoplaced yes)
		(property "Reference" "R109"
			(at 293.37 58.4199 90)
			(effects
				(font
					(size 1.27 1.27)
					(thickness 0.15)
				)
				(justify right)
			)
		)
		(property "Value" "R_110k_0402"
			(at 303.53 41.91 0)
			(effects
				(font
					(size 1.27 1.27)
					(thickness 0.15)
				)
				(justify left bottom)
				(hide yes)
			)
		)
		(property "Footprint" "antmicro-footprints:R_0402_1005Metric"
			(at 306.07 41.91 0)
			(effects
				(font
					(size 1.27 1.27)
					(thickness 0.15)
				)
				(justify left bottom)
				(hide yes)
			)
		)
		(property "Datasheet" "https://www.bourns.com/docs/product-datasheets/cr.pdf"
			(at 308.61 41.91 0)
			(effects
				(font
					(size 1.27 1.27)
					(thickness 0.15)
				)
				(justify left bottom)
				(hide yes)
			)
		)
		(property "Description" ""
			(at 290.83 62.23 0)
			(effects
				(font
					(size 1.27 1.27)
				)
				(hide yes)
			)
		)
		(property "MPN" "CR0402-FX-1103GLF"
			(at 311.15 41.91 0)
			(effects
				(font
					(size 1.27 1.27)
					(thickness 0.15)
				)
				(justify left bottom)
				(hide yes)
			)
		)
		(property "Manufacturer" "Bourns"
			(at 313.69 41.91 0)
			(effects
				(font
					(size 1.27 1.27)
					(thickness 0.15)
				)
				(justify left bottom)
				(hide yes)
			)
		)
		(property "License" "Apache-2.0"
			(at 316.23 41.91 0)
			(effects
				(font
					(size 1.27 1.27)
					(thickness 0.15)
				)
				(justify left bottom)
				(hide yes)
			)
		)
		(property "Author" "Antmicro"
			(at 318.77 41.91 0)
			(effects
				(font
					(size 1.27 1.27)
					(thickness 0.15)
				)
				(justify left bottom)
				(hide yes)
			)
		)
		(property "Val" "110k"
			(at 293.37 60.9599 90)
			(effects
				(font
					(size 1.27 1.27)
					(thickness 0.15)
				)
				(justify right)
			)
		)
		(property "Tolerance" "1%"
			(at 300.99 41.91 0)
			(effects
				(font
					(size 1.27 1.27)
				)
				(justify left bottom)
				(hide yes)
			)
		)
		(property "Public" "False"
			(at 321.31 41.91 0)
			(effects
				(font
					(size 1.27 1.27)
				)
				(justify left bottom)
				(hide yes)
			)
		)
		(pin "2"
		)
		(pin "1"
		)
		(instances
			(project "com-express-7-baseboard"
				(path ""
					(reference "R109")
					(unit 1)
				)
			)
		)
	)
	(symbol
		(lib_id "antmicropower:+1V8")
		(at 87.63 49.53 0)
		(unit 1)
		(exclude_from_sim no)
		(in_bom yes)
		(on_board yes)
		(dnp no)
		(property "Reference" "#PWR0100"
			(at 102.87 52.07 0)
			(effects
				(font
					(size 1.27 1.27)
					(thickness 0.15)
				)
				(justify left bottom)
				(hide yes)
			)
		)
		(property "Value" "+1V8"
			(at 87.63 45.72 0)
			(effects
				(font
					(size 1.27 1.27)
					(thickness 0.15)
				)
			)
		)
		(property "Footprint" ""
			(at 102.87 57.15 0)
			(effects
				(font
					(size 1.27 1.27)
					(thickness 0.15)
				)
				(justify left bottom)
				(hide yes)
			)
		)
		(property "Datasheet" ""
			(at 102.87 59.69 0)
			(effects
				(font
					(size 1.27 1.27)
					(thickness 0.15)
				)
				(justify left bottom)
				(hide yes)
			)
		)
		(property "Description" ""
			(at 87.63 49.53 0)
			(effects
				(font
					(size 1.27 1.27)
				)
				(hide yes)
			)
		)
		(property "Author" "Antmicro"
			(at 102.87 54.61 0)
			(effects
				(font
					(size 1.27 1.27)
					(thickness 0.15)
				)
				(justify left bottom)
				(hide yes)
			)
		)
		(property "License" "Apache-2.0"
			(at 102.87 57.15 0)
			(effects
				(font
					(size 1.27 1.27)
					(thickness 0.15)
				)
				(justify left bottom)
				(hide yes)
			)
		)
		(pin "1"
		)
		(instances
			(project "com-express-7-baseboard"
				(path ""
					(reference "#PWR0100")
					(unit 1)
				)
			)
		)
	)
	(symbol
		(lib_id "antmicropower:GND")
		(at 377.19 85.09 0)
		(unit 1)
		(exclude_from_sim no)
		(in_bom yes)
		(on_board yes)
		(dnp no)
		(property "Reference" "#PWR0151"
			(at 386.08 87.63 0)
			(effects
				(font
					(size 1.27 1.27)
					(thickness 0.15)
				)
				(justify left bottom)
				(hide yes)
			)
		)
		(property "Value" "GND"
			(at 377.19 88.9 0)
			(effects
				(font
					(size 1.27 1.27)
					(thickness 0.15)
				)
			)
		)
		(property "Footprint" ""
			(at 386.08 92.71 0)
			(effects
				(font
					(size 1.27 1.27)
					(thickness 0.15)
				)
				(justify left bottom)
				(hide yes)
			)
		)
		(property "Datasheet" ""
			(at 386.08 97.79 0)
			(effects
				(font
					(size 1.27 1.27)
					(thickness 0.15)
				)
				(justify left bottom)
				(hide yes)
			)
		)
		(property "Description" ""
			(at 377.19 85.09 0)
			(effects
				(font
					(size 1.27 1.27)
				)
				(hide yes)
			)
		)
		(property "Author" "Antmicro"
			(at 386.08 92.71 0)
			(effects
				(font
					(size 1.27 1.27)
					(thickness 0.15)
				)
				(justify left bottom)
				(hide yes)
			)
		)
		(property "License" "Apache-2.0"
			(at 386.08 95.25 0)
			(effects
				(font
					(size 1.27 1.27)
					(thickness 0.15)
				)
				(justify left bottom)
				(hide yes)
			)
		)
		(pin "1"
		)
		(instances
			(project "com-express-7-baseboard"
				(path ""
					(reference "#PWR0151")
					(unit 1)
				)
			)
		)
	)
	(symbol
		(lib_id "antmicropower:GND")
		(at 375.92 226.06 0)
		(mirror y)
		(unit 1)
		(exclude_from_sim no)
		(in_bom yes)
		(on_board yes)
		(dnp no)
		(property "Reference" "#PWR0152"
			(at 367.03 228.6 0)
			(effects
				(font
					(size 1.27 1.27)
					(thickness 0.15)
				)
				(justify left bottom)
				(hide yes)
			)
		)
		(property "Value" "GND"
			(at 375.92 229.87 0)
			(effects
				(font
					(size 1.27 1.27)
					(thickness 0.15)
				)
			)
		)
		(property "Footprint" ""
			(at 367.03 233.68 0)
			(effects
				(font
					(size 1.27 1.27)
					(thickness 0.15)
				)
				(justify left bottom)
				(hide yes)
			)
		)
		(property "Datasheet" ""
			(at 367.03 238.76 0)
			(effects
				(font
					(size 1.27 1.27)
					(thickness 0.15)
				)
				(justify left bottom)
				(hide yes)
			)
		)
		(property "Description" ""
			(at 375.92 226.06 0)
			(effects
				(font
					(size 1.27 1.27)
				)
				(hide yes)
			)
		)
		(property "Author" "Antmicro"
			(at 367.03 233.68 0)
			(effects
				(font
					(size 1.27 1.27)
					(thickness 0.15)
				)
				(justify left bottom)
				(hide yes)
			)
		)
		(property "License" "Apache-2.0"
			(at 367.03 236.22 0)
			(effects
				(font
					(size 1.27 1.27)
					(thickness 0.15)
				)
				(justify left bottom)
				(hide yes)
			)
		)
		(pin "1"
		)
		(instances
			(project "com-express-7-baseboard"
				(path ""
					(reference "#PWR0152")
					(unit 1)
				)
			)
		)
	)
	(symbol
		(lib_id "antmicroCapacitorspol:C_Pol_100u_10V_KEMET-T520-B")
		(at 160.02 134.62 270)
		(unit 1)
		(exclude_from_sim no)
		(in_bom yes)
		(on_board yes)
		(dnp no)
		(fields_autoplaced yes)
		(property "Reference" "C52"
			(at 162.56 134.0865 90)
			(effects
				(font
					(size 1.27 1.27)
					(thickness 0.15)
				)
				(justify left)
			)
		)
		(property "Value" "C_Pol_100u_10V_KEMET-T520-B"
			(at 157.48 148.59 0)
			(effects
				(font
					(size 1.27 1.27)
					(thickness 0.15)
				)
				(justify left bottom)
				(hide yes)
			)
		)
		(property "Footprint" "antmicro-footprints:C_Pol_EIA-B"
			(at 152.4 148.59 0)
			(effects
				(font
					(size 1.27 1.27)
					(thickness 0.15)
				)
				(justify left bottom)
				(hide yes)
			)
		)
		(property "Datasheet" "https://www.kemet.com/en/us/capacitors/product/T520B107M010ATE070.html"
			(at 149.86 148.59 0)
			(effects
				(font
					(size 1.27 1.27)
					(thickness 0.15)
				)
				(justify left bottom)
				(hide yes)
			)
		)
		(property "Description" ""
			(at 160.02 134.62 0)
			(effects
				(font
					(size 1.27 1.27)
				)
				(hide yes)
			)
		)
		(property "Val" "100u"
			(at 162.56 136.6265 90)
			(effects
				(font
					(size 1.27 1.27)
					(thickness 0.15)
				)
				(justify left)
			)
		)
		(property "MPN" "T520B107M010ATE070"
			(at 147.32 148.59 0)
			(effects
				(font
					(size 1.27 1.27)
					(thickness 0.15)
				)
				(justify left bottom)
				(hide yes)
			)
		)
		(property "Manufacturer" "KEMET"
			(at 144.78 148.59 0)
			(effects
				(font
					(size 1.27 1.27)
					(thickness 0.15)
				)
				(justify left bottom)
				(hide yes)
			)
		)
		(property "License" "Apache-2.0"
			(at 142.24 148.59 0)
			(effects
				(font
					(size 1.27 1.27)
					(thickness 0.15)
				)
				(justify left bottom)
				(hide yes)
			)
		)
		(property "Author" "Antmicro"
			(at 139.7 148.59 0)
			(effects
				(font
					(size 1.27 1.27)
					(thickness 0.15)
				)
				(justify left bottom)
				(hide yes)
			)
		)
		(property "Voltage" "10V"
			(at 162.56 139.1665 90)
			(effects
				(font
					(size 1.27 1.27)
				)
				(justify left)
			)
		)
		(property "Dielectric" "template_dielectric"
			(at 134.62 148.59 0)
			(effects
				(font
					(size 1.27 1.27)
				)
				(justify left bottom)
				(hide yes)
			)
		)
		(property "Public" "False"
			(at 132.08 148.59 0)
			(effects
				(font
					(size 1.27 1.27)
				)
				(justify left bottom)
				(hide yes)
			)
		)
		(pin "1"
		)
		(pin "2"
		)
		(instances
			(project "com-express-7-baseboard"
				(path ""
					(reference "C52")
					(unit 1)
				)
			)
		)
	)
	(symbol
		(lib_id "antmicroCapacitorspol:C_Pol_100u_10V_KEMET-T520-B")
		(at 330.2 139.7 270)
		(unit 1)
		(exclude_from_sim no)
		(in_bom yes)
		(on_board yes)
		(dnp no)
		(fields_autoplaced yes)
		(property "Reference" "C65"
			(at 332.74 139.1665 90)
			(effects
				(font
					(size 1.27 1.27)
					(thickness 0.15)
				)
				(justify left)
			)
		)
		(property "Value" "C_Pol_100u_10V_KEMET-T520-B"
			(at 327.66 153.67 0)
			(effects
				(font
					(size 1.27 1.27)
					(thickness 0.15)
				)
				(justify left bottom)
				(hide yes)
			)
		)
		(property "Footprint" "antmicro-footprints:C_Pol_EIA-B"
			(at 322.58 153.67 0)
			(effects
				(font
					(size 1.27 1.27)
					(thickness 0.15)
				)
				(justify left bottom)
				(hide yes)
			)
		)
		(property "Datasheet" "https://www.kemet.com/en/us/capacitors/product/T520B107M010ATE070.html"
			(at 320.04 153.67 0)
			(effects
				(font
					(size 1.27 1.27)
					(thickness 0.15)
				)
				(justify left bottom)
				(hide yes)
			)
		)
		(property "Description" ""
			(at 330.2 139.7 0)
			(effects
				(font
					(size 1.27 1.27)
				)
				(hide yes)
			)
		)
		(property "Val" "100u"
			(at 332.74 141.7065 90)
			(effects
				(font
					(size 1.27 1.27)
					(thickness 0.15)
				)
				(justify left)
			)
		)
		(property "MPN" "T520B107M010ATE070"
			(at 317.5 153.67 0)
			(effects
				(font
					(size 1.27 1.27)
					(thickness 0.15)
				)
				(justify left bottom)
				(hide yes)
			)
		)
		(property "Manufacturer" "KEMET"
			(at 314.96 153.67 0)
			(effects
				(font
					(size 1.27 1.27)
					(thickness 0.15)
				)
				(justify left bottom)
				(hide yes)
			)
		)
		(property "License" "Apache-2.0"
			(at 312.42 153.67 0)
			(effects
				(font
					(size 1.27 1.27)
					(thickness 0.15)
				)
				(justify left bottom)
				(hide yes)
			)
		)
		(property "Author" "Antmicro"
			(at 309.88 153.67 0)
			(effects
				(font
					(size 1.27 1.27)
					(thickness 0.15)
				)
				(justify left bottom)
				(hide yes)
			)
		)
		(property "Voltage" "10V"
			(at 332.74 144.2465 90)
			(effects
				(font
					(size 1.27 1.27)
				)
				(justify left)
			)
		)
		(property "Dielectric" "template_dielectric"
			(at 304.8 153.67 0)
			(effects
				(font
					(size 1.27 1.27)
				)
				(justify left bottom)
				(hide yes)
			)
		)
		(property "Public" "False"
			(at 302.26 153.67 0)
			(effects
				(font
					(size 1.27 1.27)
				)
				(justify left bottom)
				(hide yes)
			)
		)
		(pin "1"
		)
		(pin "2"
		)
		(instances
			(project "com-express-7-baseboard"
				(path ""
					(reference "C65")
					(unit 1)
				)
			)
		)
	)
	(symbol
		(lib_id "antmicropower:GND")
		(at 124.46 148.59 0)
		(mirror y)
		(unit 1)
		(exclude_from_sim no)
		(in_bom yes)
		(on_board yes)
		(dnp no)
		(property "Reference" "#PWR0109"
			(at 115.57 151.13 0)
			(effects
				(font
					(size 1.27 1.27)
					(thickness 0.15)
				)
				(justify left bottom)
				(hide yes)
			)
		)
		(property "Value" "GND"
			(at 124.46 152.4 0)
			(effects
				(font
					(size 1.27 1.27)
					(thickness 0.15)
				)
			)
		)
		(property "Footprint" ""
			(at 115.57 156.21 0)
			(effects
				(font
					(size 1.27 1.27)
					(thickness 0.15)
				)
				(justify left bottom)
				(hide yes)
			)
		)
		(property "Datasheet" ""
			(at 115.57 161.29 0)
			(effects
				(font
					(size 1.27 1.27)
					(thickness 0.15)
				)
				(justify left bottom)
				(hide yes)
			)
		)
		(property "Description" ""
			(at 124.46 148.59 0)
			(effects
				(font
					(size 1.27 1.27)
				)
				(hide yes)
			)
		)
		(property "Author" "Antmicro"
			(at 115.57 156.21 0)
			(effects
				(font
					(size 1.27 1.27)
					(thickness 0.15)
				)
				(justify left bottom)
				(hide yes)
			)
		)
		(property "License" "Apache-2.0"
			(at 115.57 158.75 0)
			(effects
				(font
					(size 1.27 1.27)
					(thickness 0.15)
				)
				(justify left bottom)
				(hide yes)
			)
		)
		(pin "1"
		)
		(instances
			(project "com-express-7-baseboard"
				(path ""
					(reference "#PWR0109")
					(unit 1)
				)
			)
		)
	)
	(symbol
		(lib_id "antmicropower:GND")
		(at 91.44 154.94 0)
		(mirror y)
		(unit 1)
		(exclude_from_sim no)
		(in_bom yes)
		(on_board yes)
		(dnp no)
		(property "Reference" "#PWR0103"
			(at 82.55 157.48 0)
			(effects
				(font
					(size 1.27 1.27)
					(thickness 0.15)
				)
				(justify left bottom)
				(hide yes)
			)
		)
		(property "Value" "GND"
			(at 91.44 158.75 0)
			(effects
				(font
					(size 1.27 1.27)
					(thickness 0.15)
				)
			)
		)
		(property "Footprint" ""
			(at 82.55 162.56 0)
			(effects
				(font
					(size 1.27 1.27)
					(thickness 0.15)
				)
				(justify left bottom)
				(hide yes)
			)
		)
		(property "Datasheet" ""
			(at 82.55 167.64 0)
			(effects
				(font
					(size 1.27 1.27)
					(thickness 0.15)
				)
				(justify left bottom)
				(hide yes)
			)
		)
		(property "Description" ""
			(at 91.44 154.94 0)
			(effects
				(font
					(size 1.27 1.27)
				)
				(hide yes)
			)
		)
		(property "Author" "Antmicro"
			(at 82.55 162.56 0)
			(effects
				(font
					(size 1.27 1.27)
					(thickness 0.15)
				)
				(justify left bottom)
				(hide yes)
			)
		)
		(property "License" "Apache-2.0"
			(at 82.55 165.1 0)
			(effects
				(font
					(size 1.27 1.27)
					(thickness 0.15)
				)
				(justify left bottom)
				(hide yes)
			)
		)
		(pin "1"
		)
		(instances
			(project "com-express-7-baseboard"
				(path ""
					(reference "#PWR0103")
					(unit 1)
				)
			)
		)
	)
	(symbol
		(lib_id "antmicropower:GND")
		(at 254 227.33 0)
		(unit 1)
		(exclude_from_sim no)
		(in_bom yes)
		(on_board yes)
		(dnp no)
		(property "Reference" "#PWR0466"
			(at 262.89 229.87 0)
			(effects
				(font
					(size 1.27 1.27)
					(thickness 0.15)
				)
				(justify left bottom)
				(hide yes)
			)
		)
		(property "Value" "GND"
			(at 254 231.14 0)
			(effects
				(font
					(size 1.27 1.27)
					(thickness 0.15)
				)
			)
		)
		(property "Footprint" ""
			(at 262.89 234.95 0)
			(effects
				(font
					(size 1.27 1.27)
					(thickness 0.15)
				)
				(justify left bottom)
				(hide yes)
			)
		)
		(property "Datasheet" ""
			(at 262.89 240.03 0)
			(effects
				(font
					(size 1.27 1.27)
					(thickness 0.15)
				)
				(justify left bottom)
				(hide yes)
			)
		)
		(property "Description" ""
			(at 254 227.33 0)
			(effects
				(font
					(size 1.27 1.27)
				)
				(hide yes)
			)
		)
		(property "Author" "Antmicro"
			(at 262.89 234.95 0)
			(effects
				(font
					(size 1.27 1.27)
					(thickness 0.15)
				)
				(justify left bottom)
				(hide yes)
			)
		)
		(property "License" "Apache-2.0"
			(at 262.89 237.49 0)
			(effects
				(font
					(size 1.27 1.27)
					(thickness 0.15)
				)
				(justify left bottom)
				(hide yes)
			)
		)
		(pin "1"
		)
		(instances
			(project "com-express-7-baseboard"
				(path ""
					(reference "#PWR0466")
					(unit 1)
				)
			)
		)
	)
	(symbol
		(lib_id "antmicroResistors0402:R_15k_0402")
		(at 290.83 69.85 90)
		(unit 1)
		(exclude_from_sim no)
		(in_bom yes)
		(on_board yes)
		(dnp no)
		(fields_autoplaced yes)
		(property "Reference" "R110"
			(at 293.37 66.0399 90)
			(effects
				(font
					(size 1.27 1.27)
					(thickness 0.15)
				)
				(justify right)
			)
		)
		(property "Value" "R_15k_0402"
			(at 303.53 49.53 0)
			(effects
				(font
					(size 1.27 1.27)
					(thickness 0.15)
				)
				(justify left bottom)
				(hide yes)
			)
		)
		(property "Footprint" "antmicro-footprints:R_0402_1005Metric"
			(at 306.07 49.53 0)
			(effects
				(font
					(size 1.27 1.27)
					(thickness 0.15)
				)
				(justify left bottom)
				(hide yes)
			)
		)
		(property "Datasheet" "https://www.bourns.com/docs/product-datasheets/cr.pdf"
			(at 308.61 49.53 0)
			(effects
				(font
					(size 1.27 1.27)
					(thickness 0.15)
				)
				(justify left bottom)
				(hide yes)
			)
		)
		(property "Description" ""
			(at 290.83 69.85 0)
			(effects
				(font
					(size 1.27 1.27)
				)
				(hide yes)
			)
		)
		(property "MPN" "CR0402-FX-1502GLF"
			(at 311.15 49.53 0)
			(effects
				(font
					(size 1.27 1.27)
					(thickness 0.15)
				)
				(justify left bottom)
				(hide yes)
			)
		)
		(property "Manufacturer" "Bourns"
			(at 313.69 49.53 0)
			(effects
				(font
					(size 1.27 1.27)
					(thickness 0.15)
				)
				(justify left bottom)
				(hide yes)
			)
		)
		(property "License" "Apache-2.0"
			(at 316.23 49.53 0)
			(effects
				(font
					(size 1.27 1.27)
					(thickness 0.15)
				)
				(justify left bottom)
				(hide yes)
			)
		)
		(property "Author" "Antmicro"
			(at 318.77 49.53 0)
			(effects
				(font
					(size 1.27 1.27)
					(thickness 0.15)
				)
				(justify left bottom)
				(hide yes)
			)
		)
		(property "Val" "15k"
			(at 293.37 68.5799 90)
			(effects
				(font
					(size 1.27 1.27)
					(thickness 0.15)
				)
				(justify right)
			)
		)
		(property "Tolerance" "1%"
			(at 300.99 49.53 0)
			(effects
				(font
					(size 1.27 1.27)
				)
				(justify left bottom)
				(hide yes)
			)
		)
		(property "Public" "False"
			(at 321.31 49.53 0)
			(effects
				(font
					(size 1.27 1.27)
				)
				(justify left bottom)
				(hide yes)
			)
		)
		(pin "2"
		)
		(pin "1"
		)
		(instances
			(project "com-express-7-baseboard"
				(path ""
					(reference "R110")
					(unit 1)
				)
			)
		)
	)
	(symbol
		(lib_id "antmicroCapacitors0402:C_1u_0402")
		(at 179.07 59.69 90)
		(unit 1)
		(exclude_from_sim no)
		(in_bom yes)
		(on_board yes)
		(dnp no)
		(fields_autoplaced yes)
		(property "Reference" "C56"
			(at 181.61 55.8735 90)
			(effects
				(font
					(size 1.27 1.27)
					(thickness 0.15)
				)
				(justify right)
			)
		)
		(property "Value" "C_1u_0402"
			(at 189.23 39.37 0)
			(effects
				(font
					(size 1.27 1.27)
					(thickness 0.15)
				)
				(justify left bottom)
				(hide yes)
			)
		)
		(property "Footprint" "antmicro-footprints:C_0402_1005Metric"
			(at 191.77 39.37 0)
			(effects
				(font
					(size 1.27 1.27)
					(thickness 0.15)
				)
				(justify left bottom)
				(hide yes)
			)
		)
		(property "Datasheet" "https://product.tdk.com/en/search/capacitor/ceramic/mlcc/info?part_no=C1005X6S1A105K050BC"
			(at 194.31 39.37 0)
			(effects
				(font
					(size 1.27 1.27)
					(thickness 0.15)
				)
				(justify left bottom)
				(hide yes)
			)
		)
		(property "Description" ""
			(at 179.07 59.69 0)
			(effects
				(font
					(size 1.27 1.27)
				)
				(hide yes)
			)
		)
		(property "MPN" "C1005X6S1A105K050BC"
			(at 196.85 39.37 0)
			(effects
				(font
					(size 1.27 1.27)
					(thickness 0.15)
				)
				(justify left bottom)
				(hide yes)
			)
		)
		(property "Manufacturer" "TDK"
			(at 199.39 39.37 0)
			(effects
				(font
					(size 1.27 1.27)
					(thickness 0.15)
				)
				(justify left bottom)
				(hide yes)
			)
		)
		(property "License" "Apache-2.0"
			(at 201.93 39.37 0)
			(effects
				(font
					(size 1.27 1.27)
					(thickness 0.15)
				)
				(justify left bottom)
				(hide yes)
			)
		)
		(property "Author" "Antmicro"
			(at 204.47 39.37 0)
			(effects
				(font
					(size 1.27 1.27)
					(thickness 0.15)
				)
				(justify left bottom)
				(hide yes)
			)
		)
		(property "Val" "1u"
			(at 181.61 58.4135 90)
			(effects
				(font
					(size 1.27 1.27)
					(thickness 0.15)
				)
				(justify right)
			)
		)
		(property "Voltage" ""
			(at 207.01 39.37 0)
			(effects
				(font
					(size 1.27 1.27)
				)
				(justify left bottom)
				(hide yes)
			)
		)
		(property "Dielectric" ""
			(at 209.55 39.37 0)
			(effects
				(font
					(size 1.27 1.27)
				)
				(justify left bottom)
				(hide yes)
			)
		)
		(property "Public" "False"
			(at 212.09 39.37 0)
			(effects
				(font
					(size 1.27 1.27)
				)
				(justify left bottom)
				(hide yes)
			)
		)
		(pin "1"
		)
		(pin "2"
		)
		(instances
			(project "com-express-7-baseboard"
				(path ""
					(reference "C56")
					(unit 1)
				)
			)
		)
	)
	(symbol
		(lib_id "antmicroResistors0402:R_100k_0402")
		(at 152.4 250.19 90)
		(unit 1)
		(exclude_from_sim no)
		(in_bom yes)
		(on_board yes)
		(dnp no)
		(fields_autoplaced yes)
		(property "Reference" "R101"
			(at 154.94 246.3799 90)
			(effects
				(font
					(size 1.27 1.27)
					(thickness 0.15)
				)
				(justify right)
			)
		)
		(property "Value" "R_100k_0402"
			(at 165.1 229.87 0)
			(effects
				(font
					(size 1.27 1.27)
					(thickness 0.15)
				)
				(justify left bottom)
				(hide yes)
			)
		)
		(property "Footprint" "antmicro-footprints:R_0402_1005Metric"
			(at 167.64 229.87 0)
			(effects
				(font
					(size 1.27 1.27)
					(thickness 0.15)
				)
				(justify left bottom)
				(hide yes)
			)
		)
		(property "Datasheet" "https://www.bourns.com/docs/product-datasheets/cr.pdf"
			(at 170.18 229.87 0)
			(effects
				(font
					(size 1.27 1.27)
					(thickness 0.15)
				)
				(justify left bottom)
				(hide yes)
			)
		)
		(property "Description" ""
			(at 152.4 250.19 0)
			(effects
				(font
					(size 1.27 1.27)
				)
				(hide yes)
			)
		)
		(property "MPN" "CR0402-FX-1003GLF"
			(at 172.72 229.87 0)
			(effects
				(font
					(size 1.27 1.27)
					(thickness 0.15)
				)
				(justify left bottom)
				(hide yes)
			)
		)
		(property "Manufacturer" "Bourns"
			(at 175.26 229.87 0)
			(effects
				(font
					(size 1.27 1.27)
					(thickness 0.15)
				)
				(justify left bottom)
				(hide yes)
			)
		)
		(property "License" "Apache-2.0"
			(at 177.8 229.87 0)
			(effects
				(font
					(size 1.27 1.27)
					(thickness 0.15)
				)
				(justify left bottom)
				(hide yes)
			)
		)
		(property "Author" "Antmicro"
			(at 180.34 229.87 0)
			(effects
				(font
					(size 1.27 1.27)
					(thickness 0.15)
				)
				(justify left bottom)
				(hide yes)
			)
		)
		(property "Val" "100k"
			(at 154.94 248.9199 90)
			(effects
				(font
					(size 1.27 1.27)
					(thickness 0.15)
				)
				(justify right)
			)
		)
		(property "Tolerance" "1%"
			(at 162.56 229.87 0)
			(effects
				(font
					(size 1.27 1.27)
				)
				(justify left bottom)
				(hide yes)
			)
		)
		(property "Public" "False"
			(at 182.88 229.87 0)
			(effects
				(font
					(size 1.27 1.27)
				)
				(justify left bottom)
				(hide yes)
			)
		)
		(pin "1"
		)
		(pin "2"
		)
		(instances
			(project "com-express-7-baseboard"
				(path ""
					(reference "R101")
					(unit 1)
				)
			)
		)
	)
	(symbol
		(lib_id "antmicropower:+3V3_AON")
		(at 76.2 241.3 0)
		(unit 1)
		(exclude_from_sim no)
		(in_bom yes)
		(on_board yes)
		(dnp no)
		(property "Reference" "#PWR0437"
			(at 76.2 245.11 0)
			(effects
				(font
					(size 1.27 1.27)
				)
				(hide yes)
			)
		)
		(property "Value" "+3V3_AON"
			(at 76.2 237.49 0)
			(effects
				(font
					(size 1.27 1.27)
				)
			)
		)
		(property "Footprint" ""
			(at 76.2 241.3 0)
			(effects
				(font
					(size 1.27 1.27)
				)
				(hide yes)
			)
		)
		(property "Datasheet" ""
			(at 76.2 241.3 0)
			(effects
				(font
					(size 1.27 1.27)
				)
				(hide yes)
			)
		)
		(property "Description" ""
			(at 76.2 241.3 0)
			(effects
				(font
					(size 1.27 1.27)
				)
				(hide yes)
			)
		)
		(pin "1"
		)
		(instances
			(project "com-express-7-baseboard"
				(path ""
					(reference "#PWR0437")
					(unit 1)
				)
			)
		)
	)
	(symbol
		(lib_id "antmicroTestPoints:TP_0.75mm_SMD")
		(at 257.81 246.38 0)
		(mirror x)
		(unit 1)
		(exclude_from_sim no)
		(in_bom no)
		(on_board yes)
		(dnp no)
		(property "Reference" "TP97"
			(at 261.62 246.38 0)
			(effects
				(font
					(size 1.27 1.27)
					(thickness 0.15)
				)
				(justify left)
			)
		)
		(property "Value" "TP_0.75mm_SMD"
			(at 268.605 242.57 0)
			(effects
				(font
					(size 1.27 1.27)
					(thickness 0.15)
				)
				(justify left bottom)
				(hide yes)
			)
		)
		(property "Footprint" "antmicro-footprints:TP_SMD_0.75mm"
			(at 268.605 240.03 0)
			(effects
				(font
					(size 1.27 1.27)
					(thickness 0.15)
				)
				(justify left bottom)
				(hide yes)
			)
		)
		(property "Datasheet" ""
			(at 275.59 233.68 0)
			(effects
				(font
					(size 1.27 1.27)
					(thickness 0.15)
				)
				(justify left bottom)
				(hide yes)
			)
		)
		(property "Description" ""
			(at 257.81 246.38 0)
			(effects
				(font
					(size 1.27 1.27)
				)
				(hide yes)
			)
		)
		(property "MPN" ""
			(at 268.605 234.95 0)
			(effects
				(font
					(size 1.27 1.27)
					(thickness 0.15)
				)
				(justify left bottom)
				(hide yes)
			)
		)
		(property "Manufacturer" ""
			(at 268.605 240.03 0)
			(effects
				(font
					(size 1.27 1.27)
					(thickness 0.15)
				)
				(justify left bottom)
				(hide yes)
			)
		)
		(property "Author" "Antmicro"
			(at 268.605 237.49 0)
			(effects
				(font
					(size 1.27 1.27)
					(thickness 0.15)
				)
				(justify left bottom)
				(hide yes)
			)
		)
		(property "License" "Apache-2.0"
			(at 268.605 234.95 0)
			(effects
				(font
					(size 1.27 1.27)
					(thickness 0.15)
				)
				(justify left bottom)
				(hide yes)
			)
		)
		(property "Public" "False"
			(at 267.97 232.41 0)
			(effects
				(font
					(size 1.27 1.27)
				)
				(justify left bottom)
				(hide yes)
			)
		)
		(pin "1"
		)
		(instances
			(project "com-express-7-baseboard"
				(path ""
					(reference "TP97")
					(unit 1)
				)
			)
		)
	)
	(symbol
		(lib_id "antmicroCapacitors0402:C_100n_0402")
		(at 69.85 248.92 90)
		(unit 1)
		(exclude_from_sim no)
		(in_bom yes)
		(on_board yes)
		(dnp no)
		(property "Reference" "C203"
			(at 72.39 245.1035 90)
			(effects
				(font
					(size 1.27 1.27)
					(thickness 0.15)
				)
				(justify right)
			)
		)
		(property "Value" "C_100n_0402"
			(at 80.01 228.6 0)
			(effects
				(font
					(size 1.27 1.27)
					(thickness 0.15)
				)
				(justify left bottom)
				(hide yes)
			)
		)
		(property "Footprint" "antmicro-footprints:C_0402_1005Metric"
			(at 82.55 228.6 0)
			(effects
				(font
					(size 1.27 1.27)
					(thickness 0.15)
				)
				(justify left bottom)
				(hide yes)
			)
		)
		(property "Datasheet" "https://www.murata.com/products/productdetail?partno=GRM155R61H104KE14%23"
			(at 85.09 228.6 0)
			(effects
				(font
					(size 1.27 1.27)
					(thickness 0.15)
				)
				(justify left bottom)
				(hide yes)
			)
		)
		(property "Description" ""
			(at 69.85 248.92 0)
			(effects
				(font
					(size 1.27 1.27)
				)
				(hide yes)
			)
		)
		(property "MPN" "GRM155R61H104KE14D"
			(at 87.63 228.6 0)
			(effects
				(font
					(size 1.27 1.27)
					(thickness 0.15)
				)
				(justify left bottom)
				(hide yes)
			)
		)
		(property "Manufacturer" "Murata"
			(at 90.17 228.6 0)
			(effects
				(font
					(size 1.27 1.27)
					(thickness 0.15)
				)
				(justify left bottom)
				(hide yes)
			)
		)
		(property "License" "Apache-2.0"
			(at 92.71 228.6 0)
			(effects
				(font
					(size 1.27 1.27)
					(thickness 0.15)
				)
				(justify left bottom)
				(hide yes)
			)
		)
		(property "Author" "Antmicro"
			(at 95.25 228.6 0)
			(effects
				(font
					(size 1.27 1.27)
					(thickness 0.15)
				)
				(justify left bottom)
				(hide yes)
			)
		)
		(property "Val" "100n"
			(at 72.39 247.6435 90)
			(effects
				(font
					(size 1.27 1.27)
					(thickness 0.15)
				)
				(justify right)
			)
		)
		(property "Voltage" "50V"
			(at 97.79 228.6 0)
			(effects
				(font
					(size 1.27 1.27)
				)
				(justify left bottom)
				(hide yes)
			)
		)
		(property "Dielectric" "X5R"
			(at 100.33 228.6 0)
			(effects
				(font
					(size 1.27 1.27)
				)
				(justify left bottom)
				(hide yes)
			)
		)
		(property "Public" "False"
			(at 102.87 228.6 0)
			(effects
				(font
					(size 1.27 1.27)
				)
				(justify left bottom)
				(hide yes)
			)
		)
		(pin "1"
		)
		(pin "2"
		)
		(instances
			(project "com-express-7-baseboard"
				(path ""
					(reference "C203")
					(unit 1)
				)
			)
		)
	)
	(symbol
		(lib_id "antmicropower:+5V")
		(at 67.31 129.54 0)
		(unit 1)
		(exclude_from_sim no)
		(in_bom yes)
		(on_board yes)
		(dnp no)
		(property "Reference" "#PWR093"
			(at 82.55 132.08 0)
			(effects
				(font
					(size 1.27 1.27)
					(thickness 0.15)
				)
				(justify left bottom)
				(hide yes)
			)
		)
		(property "Value" "+5V"
			(at 67.31 125.73 0)
			(effects
				(font
					(size 1.27 1.27)
					(thickness 0.15)
				)
			)
		)
		(property "Footprint" ""
			(at 82.55 137.16 0)
			(effects
				(font
					(size 1.27 1.27)
					(thickness 0.15)
				)
				(justify left bottom)
				(hide yes)
			)
		)
		(property "Datasheet" ""
			(at 82.55 139.7 0)
			(effects
				(font
					(size 1.27 1.27)
					(thickness 0.15)
				)
				(justify left bottom)
				(hide yes)
			)
		)
		(property "Description" ""
			(at 67.31 129.54 0)
			(effects
				(font
					(size 1.27 1.27)
				)
				(hide yes)
			)
		)
		(property "Author" "Antmicro"
			(at 82.55 137.16 0)
			(effects
				(font
					(size 1.27 1.27)
					(thickness 0.15)
				)
				(justify left bottom)
				(hide yes)
			)
		)
		(property "License" "Apache-2.0"
			(at 82.55 139.7 0)
			(effects
				(font
					(size 1.27 1.27)
					(thickness 0.15)
				)
				(justify left bottom)
				(hide yes)
			)
		)
		(pin "1"
		)
		(instances
			(project "com-express-7-baseboard"
				(path ""
					(reference "#PWR093")
					(unit 1)
				)
			)
		)
	)
	(symbol
		(lib_id "antmicropower:+12V_AON")
		(at 76.2 220.98 0)
		(unit 1)
		(exclude_from_sim no)
		(in_bom yes)
		(on_board yes)
		(dnp no)
		(property "Reference" "#PWR096"
			(at 76.2 224.79 0)
			(effects
				(font
					(size 1.27 1.27)
				)
				(hide yes)
			)
		)
		(property "Value" "+12V_AON"
			(at 76.2 215.9 0)
			(effects
				(font
					(size 1.27 1.27)
				)
			)
		)
		(property "Footprint" ""
			(at 76.2 220.98 0)
			(effects
				(font
					(size 1.27 1.27)
				)
				(hide yes)
			)
		)
		(property "Datasheet" ""
			(at 76.2 220.98 0)
			(effects
				(font
					(size 1.27 1.27)
				)
				(hide yes)
			)
		)
		(property "Description" ""
			(at 76.2 220.98 0)
			(effects
				(font
					(size 1.27 1.27)
				)
				(hide yes)
			)
		)
		(pin "1"
		)
		(instances
			(project "com-express-7-baseboard"
				(path ""
					(reference "#PWR096")
					(unit 1)
				)
			)
		)
	)
	(symbol
		(lib_id "antmicropower:GND")
		(at 76.2 154.94 0)
		(mirror y)
		(unit 1)
		(exclude_from_sim no)
		(in_bom yes)
		(on_board yes)
		(dnp no)
		(property "Reference" "#PWR095"
			(at 67.31 157.48 0)
			(effects
				(font
					(size 1.27 1.27)
					(thickness 0.15)
				)
				(justify left bottom)
				(hide yes)
			)
		)
		(property "Value" "GND"
			(at 76.2 158.75 0)
			(effects
				(font
					(size 1.27 1.27)
					(thickness 0.15)
				)
			)
		)
		(property "Footprint" ""
			(at 67.31 162.56 0)
			(effects
				(font
					(size 1.27 1.27)
					(thickness 0.15)
				)
				(justify left bottom)
				(hide yes)
			)
		)
		(property "Datasheet" ""
			(at 67.31 167.64 0)
			(effects
				(font
					(size 1.27 1.27)
					(thickness 0.15)
				)
				(justify left bottom)
				(hide yes)
			)
		)
		(property "Description" ""
			(at 76.2 154.94 0)
			(effects
				(font
					(size 1.27 1.27)
				)
				(hide yes)
			)
		)
		(property "Author" "Antmicro"
			(at 67.31 162.56 0)
			(effects
				(font
					(size 1.27 1.27)
					(thickness 0.15)
				)
				(justify left bottom)
				(hide yes)
			)
		)
		(property "License" "Apache-2.0"
			(at 67.31 165.1 0)
			(effects
				(font
					(size 1.27 1.27)
					(thickness 0.15)
				)
				(justify left bottom)
				(hide yes)
			)
		)
		(pin "1"
		)
		(instances
			(project "com-express-7-baseboard"
				(path ""
					(reference "#PWR095")
					(unit 1)
				)
			)
		)
	)
	(symbol
		(lib_id "antmicroResistors0402:R_30k_0402")
		(at 76.2 144.78 270)
		(unit 1)
		(exclude_from_sim no)
		(in_bom yes)
		(on_board yes)
		(dnp no)
		(property "Reference" "R87"
			(at 77.47 146.05 90)
			(effects
				(font
					(size 1.27 1.27)
					(thickness 0.15)
				)
				(justify left)
			)
		)
		(property "Value" "R_30k_0402"
			(at 63.5 165.1 0)
			(effects
				(font
					(size 1.27 1.27)
					(thickness 0.15)
				)
				(justify left bottom)
				(hide yes)
			)
		)
		(property "Footprint" "antmicro-footprints:R_0402_1005Metric"
			(at 60.96 165.1 0)
			(effects
				(font
					(size 1.27 1.27)
					(thickness 0.15)
				)
				(justify left bottom)
				(hide yes)
			)
		)
		(property "Datasheet" "https://www.bourns.com/docs/product-datasheets/cr.pdf"
			(at 58.42 165.1 0)
			(effects
				(font
					(size 1.27 1.27)
					(thickness 0.15)
				)
				(justify left bottom)
				(hide yes)
			)
		)
		(property "Description" ""
			(at 76.2 144.78 0)
			(effects
				(font
					(size 1.27 1.27)
				)
				(hide yes)
			)
		)
		(property "MPN" "CR0402-FX-3002GLF"
			(at 55.88 165.1 0)
			(effects
				(font
					(size 1.27 1.27)
					(thickness 0.15)
				)
				(justify left bottom)
				(hide yes)
			)
		)
		(property "Manufacturer" "Bourns"
			(at 53.34 165.1 0)
			(effects
				(font
					(size 1.27 1.27)
					(thickness 0.15)
				)
				(justify left bottom)
				(hide yes)
			)
		)
		(property "License" "Apache-2.0"
			(at 50.8 165.1 0)
			(effects
				(font
					(size 1.27 1.27)
					(thickness 0.15)
				)
				(justify left bottom)
				(hide yes)
			)
		)
		(property "Author" "Antmicro"
			(at 48.26 165.1 0)
			(effects
				(font
					(size 1.27 1.27)
					(thickness 0.15)
				)
				(justify left bottom)
				(hide yes)
			)
		)
		(property "Val" "30k"
			(at 77.47 148.59 90)
			(effects
				(font
					(size 1.27 1.27)
					(thickness 0.15)
				)
				(justify left)
			)
		)
		(property "Tolerance" "1%"
			(at 66.04 165.1 0)
			(effects
				(font
					(size 1.27 1.27)
				)
				(justify left bottom)
				(hide yes)
			)
		)
		(property "Public" "False"
			(at 45.72 165.1 0)
			(effects
				(font
					(size 1.27 1.27)
				)
				(justify left bottom)
				(hide yes)
			)
		)
		(pin "1"
		)
		(pin "2"
		)
		(instances
			(project "com-express-7-baseboard"
				(path ""
					(reference "R87")
					(unit 1)
				)
			)
		)
	)
	(symbol
		(lib_id "antmicroResistors0402:R_100k_0402")
		(at 93.98 232.41 90)
		(unit 1)
		(exclude_from_sim no)
		(in_bom yes)
		(on_board yes)
		(dnp no)
		(property "Reference" "R94"
			(at 92.71 228.6 90)
			(effects
				(font
					(size 1.27 1.27)
					(thickness 0.15)
				)
				(justify left)
			)
		)
		(property "Value" "R_100k_0402"
			(at 106.68 212.09 0)
			(effects
				(font
					(size 1.27 1.27)
					(thickness 0.15)
				)
				(justify left bottom)
				(hide yes)
			)
		)
		(property "Footprint" "antmicro-footprints:R_0402_1005Metric"
			(at 109.22 212.09 0)
			(effects
				(font
					(size 1.27 1.27)
					(thickness 0.15)
				)
				(justify left bottom)
				(hide yes)
			)
		)
		(property "Datasheet" "https://www.bourns.com/docs/product-datasheets/cr.pdf"
			(at 111.76 212.09 0)
			(effects
				(font
					(size 1.27 1.27)
					(thickness 0.15)
				)
				(justify left bottom)
				(hide yes)
			)
		)
		(property "Description" ""
			(at 93.98 232.41 0)
			(effects
				(font
					(size 1.27 1.27)
				)
				(hide yes)
			)
		)
		(property "MPN" "CR0402-FX-1003GLF"
			(at 114.3 212.09 0)
			(effects
				(font
					(size 1.27 1.27)
					(thickness 0.15)
				)
				(justify left bottom)
				(hide yes)
			)
		)
		(property "Manufacturer" "Bourns"
			(at 116.84 212.09 0)
			(effects
				(font
					(size 1.27 1.27)
					(thickness 0.15)
				)
				(justify left bottom)
				(hide yes)
			)
		)
		(property "License" "Apache-2.0"
			(at 119.38 212.09 0)
			(effects
				(font
					(size 1.27 1.27)
					(thickness 0.15)
				)
				(justify left bottom)
				(hide yes)
			)
		)
		(property "Author" "Antmicro"
			(at 121.92 212.09 0)
			(effects
				(font
					(size 1.27 1.27)
					(thickness 0.15)
				)
				(justify left bottom)
				(hide yes)
			)
		)
		(property "Val" "100k"
			(at 92.71 231.14 90)
			(effects
				(font
					(size 1.27 1.27)
					(thickness 0.15)
				)
				(justify left)
			)
		)
		(property "Tolerance" "1%"
			(at 104.14 212.09 0)
			(effects
				(font
					(size 1.27 1.27)
				)
				(justify left bottom)
				(hide yes)
			)
		)
		(property "Public" "False"
			(at 124.46 212.09 0)
			(effects
				(font
					(size 1.27 1.27)
				)
				(justify left bottom)
				(hide yes)
			)
		)
		(pin "1"
		)
		(pin "2"
		)
		(instances
			(project "com-express-7-baseboard"
				(path ""
					(reference "R94")
					(unit 1)
				)
			)
		)
	)
	(symbol
		(lib_id "antmicroResistors0402:R_15k_0402")
		(at 139.7 143.51 90)
		(unit 1)
		(exclude_from_sim no)
		(in_bom yes)
		(on_board yes)
		(dnp no)
		(fields_autoplaced yes)
		(property "Reference" "R100"
			(at 142.24 139.6999 90)
			(effects
				(font
					(size 1.27 1.27)
					(thickness 0.15)
				)
				(justify right)
			)
		)
		(property "Value" "R_15k_0402"
			(at 152.4 123.19 0)
			(effects
				(font
					(size 1.27 1.27)
					(thickness 0.15)
				)
				(justify left bottom)
				(hide yes)
			)
		)
		(property "Footprint" "antmicro-footprints:R_0402_1005Metric"
			(at 154.94 123.19 0)
			(effects
				(font
					(size 1.27 1.27)
					(thickness 0.15)
				)
				(justify left bottom)
				(hide yes)
			)
		)
		(property "Datasheet" "https://www.bourns.com/docs/product-datasheets/cr.pdf"
			(at 157.48 123.19 0)
			(effects
				(font
					(size 1.27 1.27)
					(thickness 0.15)
				)
				(justify left bottom)
				(hide yes)
			)
		)
		(property "Description" ""
			(at 139.7 143.51 0)
			(effects
				(font
					(size 1.27 1.27)
				)
				(hide yes)
			)
		)
		(property "MPN" "CR0402-FX-1502GLF"
			(at 160.02 123.19 0)
			(effects
				(font
					(size 1.27 1.27)
					(thickness 0.15)
				)
				(justify left bottom)
				(hide yes)
			)
		)
		(property "Manufacturer" "Bourns"
			(at 162.56 123.19 0)
			(effects
				(font
					(size 1.27 1.27)
					(thickness 0.15)
				)
				(justify left bottom)
				(hide yes)
			)
		)
		(property "License" "Apache-2.0"
			(at 165.1 123.19 0)
			(effects
				(font
					(size 1.27 1.27)
					(thickness 0.15)
				)
				(justify left bottom)
				(hide yes)
			)
		)
		(property "Author" "Antmicro"
			(at 167.64 123.19 0)
			(effects
				(font
					(size 1.27 1.27)
					(thickness 0.15)
				)
				(justify left bottom)
				(hide yes)
			)
		)
		(property "Val" "15k"
			(at 142.24 142.2399 90)
			(effects
				(font
					(size 1.27 1.27)
					(thickness 0.15)
				)
				(justify right)
			)
		)
		(property "Tolerance" "1%"
			(at 149.86 123.19 0)
			(effects
				(font
					(size 1.27 1.27)
				)
				(justify left bottom)
				(hide yes)
			)
		)
		(property "Public" "False"
			(at 170.18 123.19 0)
			(effects
				(font
					(size 1.27 1.27)
				)
				(justify left bottom)
				(hide yes)
			)
		)
		(pin "1"
		)
		(pin "2"
		)
		(instances
			(project "com-express-7-baseboard"
				(path ""
					(reference "R100")
					(unit 1)
				)
			)
		)
	)
	(symbol
		(lib_id "antmicropower:+5V_AON")
		(at 245.11 196.85 0)
		(unit 1)
		(exclude_from_sim no)
		(in_bom yes)
		(on_board yes)
		(dnp no)
		(property "Reference" "#PWR0460"
			(at 245.11 200.66 0)
			(effects
				(font
					(size 1.27 1.27)
				)
				(hide yes)
			)
		)
		(property "Value" "+5V_AON"
			(at 245.11 193.04 0)
			(effects
				(font
					(size 1.27 1.27)
				)
			)
		)
		(property "Footprint" ""
			(at 245.11 196.85 0)
			(effects
				(font
					(size 1.27 1.27)
				)
				(hide yes)
			)
		)
		(property "Datasheet" ""
			(at 245.11 196.85 0)
			(effects
				(font
					(size 1.27 1.27)
				)
				(hide yes)
			)
		)
		(property "Description" ""
			(at 245.11 196.85 0)
			(effects
				(font
					(size 1.27 1.27)
				)
				(hide yes)
			)
		)
		(pin "1"
		)
		(instances
			(project "com-express-7-baseboard"
				(path ""
					(reference "#PWR0460")
					(unit 1)
				)
			)
		)
	)
	(symbol
		(lib_id "antmicroTransistorsBipolarSingle:MMBT3904LT1G")
		(at 274.32 257.81 0)
		(unit 1)
		(exclude_from_sim no)
		(in_bom yes)
		(on_board yes)
		(dnp no)
		(fields_autoplaced yes)
		(property "Reference" "Q13"
			(at 283.21 256.54 0)
			(effects
				(font
					(size 1.27 1.27)
					(thickness 0.15)
				)
				(justify left)
			)
		)
		(property "Value" "MMBT3904LT1G"
			(at 289.56 267.97 0)
			(effects
				(font
					(size 1.27 1.27)
					(thickness 0.15)
				)
				(justify left bottom)
				(hide yes)
			)
		)
		(property "Footprint" "antmicro-footprints:SOT-23-3"
			(at 289.56 270.51 0)
			(effects
				(font
					(size 1.27 1.27)
					(thickness 0.15)
				)
				(justify left bottom)
				(hide yes)
			)
		)
		(property "Datasheet" "https://eu.mouser.com/datasheet/2/308/1/MMBT3904LT1_D-2316262.pdf"
			(at 289.56 273.05 0)
			(effects
				(font
					(size 1.27 1.27)
					(thickness 0.15)
				)
				(justify left bottom)
				(hide yes)
			)
		)
		(property "Description" ""
			(at 274.32 257.81 0)
			(effects
				(font
					(size 1.27 1.27)
				)
				(hide yes)
			)
		)
		(property "MPN" "MMBT3904LT1G"
			(at 283.21 259.08 0)
			(effects
				(font
					(size 1.27 1.27)
					(thickness 0.15)
				)
				(justify left)
			)
		)
		(property "Manufacturer" "Onsemi"
			(at 289.56 275.59 0)
			(effects
				(font
					(size 1.27 1.27)
					(thickness 0.15)
				)
				(justify left bottom)
				(hide yes)
			)
		)
		(property "Author" "Antmicro"
			(at 289.56 278.13 0)
			(effects
				(font
					(size 1.27 1.27)
					(thickness 0.15)
				)
				(justify left bottom)
				(hide yes)
			)
		)
		(property "License" "Apache-2.0"
			(at 289.56 280.67 0)
			(effects
				(font
					(size 1.27 1.27)
					(thickness 0.15)
				)
				(justify left bottom)
				(hide yes)
			)
		)
		(property "Public" "False"
			(at 297.18 278.13 0)
			(effects
				(font
					(size 1.27 1.27)
				)
				(justify left bottom)
				(hide yes)
			)
		)
		(pin "2"
		)
		(pin "1"
		)
		(pin "3"
		)
		(instances
			(project "com-express-7-baseboard"
				(path ""
					(reference "Q13")
					(unit 1)
				)
			)
		)
	)
	(symbol
		(lib_id "antmicroDCDCConverters:TPS56C230")
		(at 105.41 124.46 0)
		(unit 1)
		(exclude_from_sim no)
		(in_bom yes)
		(on_board yes)
		(dnp no)
		(fields_autoplaced yes)
		(property "Reference" "U19"
			(at 114.3 116.84 0)
			(effects
				(font
					(size 1.27 1.27)
					(thickness 0.15)
				)
			)
		)
		(property "Value" "TPS56C230"
			(at 114.3 119.38 0)
			(effects
				(font
					(size 1.27 1.27)
					(thickness 0.15)
				)
				(hide yes)
			)
		)
		(property "Footprint" "antmicro-footprints:QFN-20-1EP_3x3mm_P0.45mm_TPS56xxxx"
			(at 138.43 132.08 0)
			(effects
				(font
					(size 1.27 1.27)
					(thickness 0.15)
				)
				(justify left bottom)
				(hide yes)
			)
		)
		(property "Datasheet" "https://www.ti.com/lit/ds/symlink/tps56c230.pdf?ts=1672843259715&ref_url=https%253A%252F%252Fwww.ti.com%252Fproduct%252FTPS56C230"
			(at 138.43 134.62 0)
			(effects
				(font
					(size 1.27 1.27)
					(thickness 0.15)
				)
				(justify left bottom)
				(hide yes)
			)
		)
		(property "Description" ""
			(at 105.41 124.46 0)
			(effects
				(font
					(size 1.27 1.27)
				)
				(hide yes)
			)
		)
		(property "Manufacturer" "Texas Instruments"
			(at 138.43 137.16 0)
			(effects
				(font
					(size 1.27 1.27)
					(thickness 0.15)
				)
				(justify left bottom)
				(hide yes)
			)
		)
		(property "MPN" "TPS56C230RJER"
			(at 114.3 119.38 0)
			(effects
				(font
					(size 1.27 1.27)
					(thickness 0.15)
				)
			)
		)
		(property "Author" "Antmicro"
			(at 138.43 142.24 0)
			(effects
				(font
					(size 1.27 1.27)
					(thickness 0.15)
				)
				(justify left bottom)
				(hide yes)
			)
		)
		(property "License" "Apache-2.0"
			(at 138.43 144.78 0)
			(effects
				(font
					(size 1.27 1.27)
					(thickness 0.15)
				)
				(justify left bottom)
				(hide yes)
			)
		)
		(pin "20"
		)
		(pin "2"
		)
		(pin "21"
		)
		(pin "17"
		)
		(pin "19"
		)
		(pin "6"
		)
		(pin "18"
		)
		(pin "8"
		)
		(pin "9"
		)
		(pin "3"
		)
		(pin "13"
		)
		(pin "12"
		)
		(pin "4"
		)
		(pin "16"
		)
		(pin "14"
		)
		(pin "11"
		)
		(pin "15"
		)
		(pin "5"
		)
		(pin "10"
		)
		(pin "7"
		)
		(pin "1"
		)
		(instances
			(project "com-express-7-baseboard"
				(path ""
					(reference "U19")
					(unit 1)
				)
			)
		)
	)
	(symbol
		(lib_id "antmicroResistors0402:R_0R_0402")
		(at 360.68 82.55 0)
		(unit 1)
		(exclude_from_sim no)
		(in_bom yes)
		(on_board yes)
		(dnp yes)
		(property "Reference" "R115"
			(at 363.22 85.09 0)
			(effects
				(font
					(size 1.27 1.27)
					(thickness 0.15)
				)
			)
		)
		(property "Value" "R_0R_0402"
			(at 381 95.25 0)
			(effects
				(font
					(size 1.27 1.27)
					(thickness 0.15)
				)
				(justify left bottom)
				(hide yes)
			)
		)
		(property "Footprint" "antmicro-footprints:R_0402_1005Metric"
			(at 381 97.79 0)
			(effects
				(font
					(size 1.27 1.27)
					(thickness 0.15)
				)
				(justify left bottom)
				(hide yes)
			)
		)
		(property "Datasheet" "https://industrial.panasonic.com/cdbs/www-data/pdf/RDA0000/AOA0000C301.pdf"
			(at 381 100.33 0)
			(effects
				(font
					(size 1.27 1.27)
					(thickness 0.15)
				)
				(justify left bottom)
				(hide yes)
			)
		)
		(property "Description" ""
			(at 360.68 82.55 0)
			(effects
				(font
					(size 1.27 1.27)
				)
				(hide yes)
			)
		)
		(property "MPN" "ERJ2GE0R00X"
			(at 381 102.87 0)
			(effects
				(font
					(size 1.27 1.27)
					(thickness 0.15)
				)
				(justify left bottom)
				(hide yes)
			)
		)
		(property "Manufacturer" "Panasonic"
			(at 381 105.41 0)
			(effects
				(font
					(size 1.27 1.27)
					(thickness 0.15)
				)
				(justify left bottom)
				(hide yes)
			)
		)
		(property "License" "Apache-2.0"
			(at 381 107.95 0)
			(effects
				(font
					(size 1.27 1.27)
					(thickness 0.15)
				)
				(justify left bottom)
				(hide yes)
			)
		)
		(property "Author" "Antmicro"
			(at 381 110.49 0)
			(effects
				(font
					(size 1.27 1.27)
					(thickness 0.15)
				)
				(justify left bottom)
				(hide yes)
			)
		)
		(property "Val" "0R"
			(at 367.03 81.28 0)
			(effects
				(font
					(size 1.27 1.27)
					(thickness 0.15)
				)
			)
		)
		(property "Tolerance" "~"
			(at 381 92.71 0)
			(effects
				(font
					(size 1.27 1.27)
				)
				(justify left bottom)
				(hide yes)
			)
		)
		(property "Current" "1A"
			(at 381 113.03 0)
			(effects
				(font
					(size 1.27 1.27)
					(thickness 0.15)
				)
				(justify left bottom)
				(hide yes)
			)
		)
		(property "Public" "False"
			(at 381 113.03 0)
			(effects
				(font
					(size 1.27 1.27)
				)
				(justify left bottom)
				(hide yes)
			)
		)
		(pin "1"
		)
		(pin "2"
		)
		(instances
			(project "com-express-7-baseboard"
				(path ""
					(reference "R115")
					(unit 1)
				)
			)
		)
	)
	(symbol
		(lib_id "antmicropower:GND")
		(at 152.4 250.19 0)
		(mirror y)
		(unit 1)
		(exclude_from_sim no)
		(in_bom yes)
		(on_board yes)
		(dnp no)
		(property "Reference" "#PWR0114"
			(at 143.51 252.73 0)
			(effects
				(font
					(size 1.27 1.27)
					(thickness 0.15)
				)
				(justify left bottom)
				(hide yes)
			)
		)
		(property "Value" "GND"
			(at 152.4 254 0)
			(effects
				(font
					(size 1.27 1.27)
					(thickness 0.15)
				)
			)
		)
		(property "Footprint" ""
			(at 143.51 257.81 0)
			(effects
				(font
					(size 1.27 1.27)
					(thickness 0.15)
				)
				(justify left bottom)
				(hide yes)
			)
		)
		(property "Datasheet" ""
			(at 143.51 262.89 0)
			(effects
				(font
					(size 1.27 1.27)
					(thickness 0.15)
				)
				(justify left bottom)
				(hide yes)
			)
		)
		(property "Description" ""
			(at 152.4 250.19 0)
			(effects
				(font
					(size 1.27 1.27)
				)
				(hide yes)
			)
		)
		(property "Author" "Antmicro"
			(at 143.51 257.81 0)
			(effects
				(font
					(size 1.27 1.27)
					(thickness 0.15)
				)
				(justify left bottom)
				(hide yes)
			)
		)
		(property "License" "Apache-2.0"
			(at 143.51 260.35 0)
			(effects
				(font
					(size 1.27 1.27)
					(thickness 0.15)
				)
				(justify left bottom)
				(hide yes)
			)
		)
		(pin "1"
		)
		(instances
			(project "com-express-7-baseboard"
				(path ""
					(reference "#PWR0114")
					(unit 1)
				)
			)
		)
	)
	(symbol
		(lib_id "antmicropower:GND")
		(at 52.07 254 0)
		(unit 1)
		(exclude_from_sim no)
		(in_bom yes)
		(on_board yes)
		(dnp no)
		(property "Reference" "#PWR0438"
			(at 60.96 256.54 0)
			(effects
				(font
					(size 1.27 1.27)
					(thickness 0.15)
				)
				(justify left bottom)
				(hide yes)
			)
		)
		(property "Value" "GND"
			(at 52.07 257.81 0)
			(effects
				(font
					(size 1.27 1.27)
					(thickness 0.15)
				)
			)
		)
		(property "Footprint" ""
			(at 60.96 261.62 0)
			(effects
				(font
					(size 1.27 1.27)
					(thickness 0.15)
				)
				(justify left bottom)
				(hide yes)
			)
		)
		(property "Datasheet" ""
			(at 60.96 266.7 0)
			(effects
				(font
					(size 1.27 1.27)
					(thickness 0.15)
				)
				(justify left bottom)
				(hide yes)
			)
		)
		(property "Description" ""
			(at 52.07 254 0)
			(effects
				(font
					(size 1.27 1.27)
				)
				(hide yes)
			)
		)
		(property "Author" "Antmicro"
			(at 60.96 261.62 0)
			(effects
				(font
					(size 1.27 1.27)
					(thickness 0.15)
				)
				(justify left bottom)
				(hide yes)
			)
		)
		(property "License" "Apache-2.0"
			(at 60.96 264.16 0)
			(effects
				(font
					(size 1.27 1.27)
					(thickness 0.15)
				)
				(justify left bottom)
				(hide yes)
			)
		)
		(pin "1"
		)
		(instances
			(project "com-express-7-baseboard"
				(path ""
					(reference "#PWR0438")
					(unit 1)
				)
			)
		)
	)
	(symbol
		(lib_id "antmicropower:GND")
		(at 351.79 148.59 0)
		(unit 1)
		(exclude_from_sim no)
		(in_bom yes)
		(on_board yes)
		(dnp no)
		(property "Reference" "#PWR0148"
			(at 360.68 151.13 0)
			(effects
				(font
					(size 1.27 1.27)
					(thickness 0.15)
				)
				(justify left bottom)
				(hide yes)
			)
		)
		(property "Value" "GND"
			(at 351.79 152.4 0)
			(effects
				(font
					(size 1.27 1.27)
					(thickness 0.15)
				)
			)
		)
		(property "Footprint" ""
			(at 360.68 156.21 0)
			(effects
				(font
					(size 1.27 1.27)
					(thickness 0.15)
				)
				(justify left bottom)
				(hide yes)
			)
		)
		(property "Datasheet" ""
			(at 360.68 161.29 0)
			(effects
				(font
					(size 1.27 1.27)
					(thickness 0.15)
				)
				(justify left bottom)
				(hide yes)
			)
		)
		(property "Description" ""
			(at 351.79 148.59 0)
			(effects
				(font
					(size 1.27 1.27)
				)
				(hide yes)
			)
		)
		(property "Author" "Antmicro"
			(at 360.68 156.21 0)
			(effects
				(font
					(size 1.27 1.27)
					(thickness 0.15)
				)
				(justify left bottom)
				(hide yes)
			)
		)
		(property "License" "Apache-2.0"
			(at 360.68 158.75 0)
			(effects
				(font
					(size 1.27 1.27)
					(thickness 0.15)
				)
				(justify left bottom)
				(hide yes)
			)
		)
		(pin "1"
		)
		(instances
			(project "com-express-7-baseboard"
				(path ""
					(reference "#PWR0148")
					(unit 1)
				)
			)
		)
	)
	(symbol
		(lib_id "antmicroFuses:F_12A_1206")
		(at 40.64 223.52 0)
		(unit 1)
		(exclude_from_sim no)
		(in_bom yes)
		(on_board yes)
		(dnp no)
		(fields_autoplaced yes)
		(property "Reference" "F1"
			(at 43.18 218.44 0)
			(effects
				(font
					(size 1.27 1.27)
					(thickness 0.15)
				)
			)
		)
		(property "Value" "F_12A_1206"
			(at 62.23 231.14 0)
			(effects
				(font
					(size 1.27 1.27)
					(thickness 0.15)
				)
				(justify left bottom)
				(hide yes)
			)
		)
		(property "Footprint" "antmicro-footprints:F_1206_3216Metric"
			(at 62.23 233.68 0)
			(effects
				(font
					(size 1.27 1.27)
					(thickness 0.15)
				)
				(justify left bottom)
				(hide yes)
			)
		)
		(property "Datasheet" "https://us.schurter.com/pdf/english/typ_UST_1206.pdf"
			(at 62.23 236.22 0)
			(effects
				(font
					(size 1.27 1.27)
					(thickness 0.15)
				)
				(justify left bottom)
				(hide yes)
			)
		)
		(property "Description" ""
			(at 40.64 223.52 0)
			(effects
				(font
					(size 1.27 1.27)
				)
				(hide yes)
			)
		)
		(property "Manufacturer" "Schurter"
			(at 62.23 238.76 0)
			(effects
				(font
					(size 1.27 1.27)
					(thickness 0.15)
				)
				(justify left bottom)
				(hide yes)
			)
		)
		(property "MPN" "3413.0329.22"
			(at 43.18 220.98 0)
			(effects
				(font
					(size 1.27 1.27)
					(thickness 0.15)
				)
			)
		)
		(property "Author" "Antmicro"
			(at 62.23 243.84 0)
			(effects
				(font
					(size 1.27 1.27)
					(thickness 0.15)
				)
				(justify left bottom)
				(hide yes)
			)
		)
		(property "License" "Apache-2.0"
			(at 62.23 246.38 0)
			(effects
				(font
					(size 1.27 1.27)
					(thickness 0.15)
				)
				(justify left bottom)
				(hide yes)
			)
		)
		(pin "1"
		)
		(pin "2"
		)
		(instances
			(project "com-express-7-baseboard"
				(path ""
					(reference "F1")
					(unit 1)
				)
			)
		)
	)
	(symbol
		(lib_id "antmicropower:GND")
		(at 48.26 132.08 0)
		(mirror y)
		(unit 1)
		(exclude_from_sim no)
		(in_bom yes)
		(on_board yes)
		(dnp no)
		(property "Reference" "#PWR089"
			(at 39.37 134.62 0)
			(effects
				(font
					(size 1.27 1.27)
					(thickness 0.15)
				)
				(justify left bottom)
				(hide yes)
			)
		)
		(property "Value" "GND"
			(at 48.26 135.89 0)
			(effects
				(font
					(size 1.27 1.27)
					(thickness 0.15)
				)
			)
		)
		(property "Footprint" ""
			(at 39.37 139.7 0)
			(effects
				(font
					(size 1.27 1.27)
					(thickness 0.15)
				)
				(justify left bottom)
				(hide yes)
			)
		)
		(property "Datasheet" ""
			(at 39.37 144.78 0)
			(effects
				(font
					(size 1.27 1.27)
					(thickness 0.15)
				)
				(justify left bottom)
				(hide yes)
			)
		)
		(property "Description" ""
			(at 48.26 132.08 0)
			(effects
				(font
					(size 1.27 1.27)
				)
				(hide yes)
			)
		)
		(property "Author" "Antmicro"
			(at 39.37 139.7 0)
			(effects
				(font
					(size 1.27 1.27)
					(thickness 0.15)
				)
				(justify left bottom)
				(hide yes)
			)
		)
		(property "License" "Apache-2.0"
			(at 39.37 142.24 0)
			(effects
				(font
					(size 1.27 1.27)
					(thickness 0.15)
				)
				(justify left bottom)
				(hide yes)
			)
		)
		(pin "1"
		)
		(instances
			(project "com-express-7-baseboard"
				(path ""
					(reference "#PWR089")
					(unit 1)
				)
			)
		)
	)
	(symbol
		(lib_id "antmicroResistors0402:R_68k_0402")
		(at 91.44 144.78 90)
		(unit 1)
		(exclude_from_sim no)
		(in_bom yes)
		(on_board yes)
		(dnp yes)
		(fields_autoplaced yes)
		(property "Reference" "R91"
			(at 93.98 139.6999 90)
			(effects
				(font
					(size 1.27 1.27)
					(thickness 0.15)
				)
				(justify right)
			)
		)
		(property "Value" "R_68k_0402"
			(at 104.14 124.46 0)
			(effects
				(font
					(size 1.27 1.27)
					(thickness 0.15)
				)
				(justify left bottom)
				(hide yes)
			)
		)
		(property "Footprint" "antmicro-footprints:R_0402_1005Metric"
			(at 106.68 124.46 0)
			(effects
				(font
					(size 1.27 1.27)
					(thickness 0.15)
				)
				(justify left bottom)
				(hide yes)
			)
		)
		(property "Datasheet" "https://www.bourns.com/docs/product-datasheets/cr.pdf"
			(at 109.22 124.46 0)
			(effects
				(font
					(size 1.27 1.27)
					(thickness 0.15)
				)
				(justify left bottom)
				(hide yes)
			)
		)
		(property "Description" ""
			(at 91.44 144.78 0)
			(effects
				(font
					(size 1.27 1.27)
				)
				(hide yes)
			)
		)
		(property "MPN" "CR0402-FX-6802GLF"
			(at 111.76 124.46 0)
			(effects
				(font
					(size 1.27 1.27)
					(thickness 0.15)
				)
				(justify left bottom)
				(hide yes)
			)
		)
		(property "Manufacturer" "Bourns"
			(at 114.3 124.46 0)
			(effects
				(font
					(size 1.27 1.27)
					(thickness 0.15)
				)
				(justify left bottom)
				(hide yes)
			)
		)
		(property "License" "Apache-2.0"
			(at 116.84 124.46 0)
			(effects
				(font
					(size 1.27 1.27)
					(thickness 0.15)
				)
				(justify left bottom)
				(hide yes)
			)
		)
		(property "Author" "Antmicro"
			(at 119.38 124.46 0)
			(effects
				(font
					(size 1.27 1.27)
					(thickness 0.15)
				)
				(justify left bottom)
				(hide yes)
			)
		)
		(property "Val" "68k"
			(at 93.98 142.2399 90)
			(effects
				(font
					(size 1.27 1.27)
					(thickness 0.15)
				)
				(justify right)
			)
		)
		(property "Tolerance" "1%"
			(at 101.6 124.46 0)
			(effects
				(font
					(size 1.27 1.27)
				)
				(justify left bottom)
				(hide yes)
			)
		)
		(property "Public" "False"
			(at 121.92 124.46 0)
			(effects
				(font
					(size 1.27 1.27)
				)
				(justify left bottom)
				(hide yes)
			)
		)
		(pin "1"
		)
		(pin "2"
		)
		(instances
			(project "com-express-7-baseboard"
				(path ""
					(reference "R91")
					(unit 1)
				)
			)
		)
	)
	(symbol
		(lib_id "antmicropower:+12V")
		(at 355.6 76.2 0)
		(unit 1)
		(exclude_from_sim no)
		(in_bom yes)
		(on_board yes)
		(dnp no)
		(property "Reference" "#PWR0144"
			(at 355.6 80.01 0)
			(effects
				(font
					(size 1.27 1.27)
				)
				(hide yes)
			)
		)
		(property "Value" "+12V"
			(at 352.425 72.39 0)
			(effects
				(font
					(size 1.27 1.27)
				)
				(justify left)
			)
		)
		(property "Footprint" ""
			(at 355.6 76.2 0)
			(effects
				(font
					(size 1.27 1.27)
				)
				(hide yes)
			)
		)
		(property "Datasheet" ""
			(at 355.6 76.2 0)
			(effects
				(font
					(size 1.27 1.27)
				)
				(hide yes)
			)
		)
		(property "Description" ""
			(at 355.6 76.2 0)
			(effects
				(font
					(size 1.27 1.27)
				)
				(hide yes)
			)
		)
		(pin "1"
		)
		(instances
			(project "com-express-7-baseboard"
				(path ""
					(reference "#PWR0144")
					(unit 1)
				)
			)
		)
	)
	(symbol
		(lib_id "antmicropower:GND")
		(at 330.2 148.59 0)
		(unit 1)
		(exclude_from_sim no)
		(in_bom yes)
		(on_board yes)
		(dnp no)
		(property "Reference" "#PWR0141"
			(at 339.09 151.13 0)
			(effects
				(font
					(size 1.27 1.27)
					(thickness 0.15)
				)
				(justify left bottom)
				(hide yes)
			)
		)
		(property "Value" "GND"
			(at 330.2 152.4 0)
			(effects
				(font
					(size 1.27 1.27)
					(thickness 0.15)
				)
			)
		)
		(property "Footprint" ""
			(at 339.09 156.21 0)
			(effects
				(font
					(size 1.27 1.27)
					(thickness 0.15)
				)
				(justify left bottom)
				(hide yes)
			)
		)
		(property "Datasheet" ""
			(at 339.09 161.29 0)
			(effects
				(font
					(size 1.27 1.27)
					(thickness 0.15)
				)
				(justify left bottom)
				(hide yes)
			)
		)
		(property "Description" ""
			(at 330.2 148.59 0)
			(effects
				(font
					(size 1.27 1.27)
				)
				(hide yes)
			)
		)
		(property "Author" "Antmicro"
			(at 339.09 156.21 0)
			(effects
				(font
					(size 1.27 1.27)
					(thickness 0.15)
				)
				(justify left bottom)
				(hide yes)
			)
		)
		(property "License" "Apache-2.0"
			(at 339.09 158.75 0)
			(effects
				(font
					(size 1.27 1.27)
					(thickness 0.15)
				)
				(justify left bottom)
				(hide yes)
			)
		)
		(pin "1"
		)
		(instances
			(project "com-express-7-baseboard"
				(path ""
					(reference "#PWR0141")
					(unit 1)
				)
			)
		)
	)
	(symbol
		(lib_id "antmicropower:GND")
		(at 367.03 226.06 0)
		(unit 1)
		(exclude_from_sim no)
		(in_bom yes)
		(on_board yes)
		(dnp no)
		(property "Reference" "#PWR0150"
			(at 375.92 228.6 0)
			(effects
				(font
					(size 1.27 1.27)
					(thickness 0.15)
				)
				(justify left bottom)
				(hide yes)
			)
		)
		(property "Value" "GND"
			(at 367.03 229.87 0)
			(effects
				(font
					(size 1.27 1.27)
					(thickness 0.15)
				)
			)
		)
		(property "Footprint" ""
			(at 375.92 233.68 0)
			(effects
				(font
					(size 1.27 1.27)
					(thickness 0.15)
				)
				(justify left bottom)
				(hide yes)
			)
		)
		(property "Datasheet" ""
			(at 375.92 238.76 0)
			(effects
				(font
					(size 1.27 1.27)
					(thickness 0.15)
				)
				(justify left bottom)
				(hide yes)
			)
		)
		(property "Description" ""
			(at 367.03 226.06 0)
			(effects
				(font
					(size 1.27 1.27)
				)
				(hide yes)
			)
		)
		(property "Author" "Antmicro"
			(at 375.92 233.68 0)
			(effects
				(font
					(size 1.27 1.27)
					(thickness 0.15)
				)
				(justify left bottom)
				(hide yes)
			)
		)
		(property "License" "Apache-2.0"
			(at 375.92 236.22 0)
			(effects
				(font
					(size 1.27 1.27)
					(thickness 0.15)
				)
				(justify left bottom)
				(hide yes)
			)
		)
		(pin "1"
		)
		(instances
			(project "com-express-7-baseboard"
				(path ""
					(reference "#PWR0150")
					(unit 1)
				)
			)
		)
	)
	(symbol
		(lib_id "antmicropower:VCC")
		(at 35.56 214.63 0)
		(unit 1)
		(exclude_from_sim no)
		(in_bom yes)
		(on_board yes)
		(dnp no)
		(property "Reference" "#PWR086"
			(at 35.56 218.44 0)
			(effects
				(font
					(size 1.27 1.27)
				)
				(hide yes)
			)
		)
		(property "Value" "VCC"
			(at 35.56 210.82 0)
			(effects
				(font
					(size 1.27 1.27)
				)
			)
		)
		(property "Footprint" ""
			(at 35.56 214.63 0)
			(effects
				(font
					(size 1.27 1.27)
				)
				(hide yes)
			)
		)
		(property "Datasheet" ""
			(at 35.56 214.63 0)
			(effects
				(font
					(size 1.27 1.27)
				)
				(hide yes)
			)
		)
		(property "Description" ""
			(at 35.56 214.63 0)
			(effects
				(font
					(size 1.27 1.27)
				)
				(hide yes)
			)
		)
		(pin "1"
		)
		(instances
			(project "com-express-7-baseboard"
				(path ""
					(reference "#PWR086")
					(unit 1)
				)
			)
		)
	)
	(symbol
		(lib_id "antmicropower:+3V3")
		(at 104.14 43.18 0)
		(unit 1)
		(exclude_from_sim no)
		(in_bom yes)
		(on_board yes)
		(dnp no)
		(fields_autoplaced yes)
		(property "Reference" "#PWR0105"
			(at 119.38 43.18 0)
			(effects
				(font
					(size 1.27 1.27)
					(thickness 0.15)
				)
				(justify left bottom)
				(hide yes)
			)
		)
		(property "Value" "+3V3"
			(at 104.14 38.1 0)
			(effects
				(font
					(size 1.27 1.27)
					(thickness 0.15)
				)
			)
		)
		(property "Footprint" ""
			(at 119.38 50.8 0)
			(effects
				(font
					(size 1.27 1.27)
					(thickness 0.15)
				)
				(justify left bottom)
				(hide yes)
			)
		)
		(property "Datasheet" ""
			(at 119.38 53.34 0)
			(effects
				(font
					(size 1.27 1.27)
					(thickness 0.15)
				)
				(justify left bottom)
				(hide yes)
			)
		)
		(property "Description" ""
			(at 104.14 43.18 0)
			(effects
				(font
					(size 1.27 1.27)
				)
				(hide yes)
			)
		)
		(property "Author" "Antmicro"
			(at 119.38 45.72 0)
			(effects
				(font
					(size 1.27 1.27)
					(thickness 0.15)
				)
				(justify left bottom)
				(hide yes)
			)
		)
		(property "License" "Apache-2.0"
			(at 119.38 48.26 0)
			(effects
				(font
					(size 1.27 1.27)
					(thickness 0.15)
				)
				(justify left bottom)
				(hide yes)
			)
		)
		(pin "1"
		)
		(instances
			(project "com-express-7-baseboard"
				(path ""
					(reference "#PWR0105")
					(unit 1)
				)
			)
		)
	)
	(symbol
		(lib_id "antmicropower:PWR_FLAG")
		(at 346.71 53.34 0)
		(unit 1)
		(exclude_from_sim no)
		(in_bom yes)
		(on_board yes)
		(dnp no)
		(property "Reference" "#FLG012"
			(at 346.71 51.435 0)
			(effects
				(font
					(size 1.27 1.27)
				)
				(hide yes)
			)
		)
		(property "Value" "PWR_FLAG"
			(at 346.71 49.53 0)
			(effects
				(font
					(size 1.27 1.27)
				)
			)
		)
		(property "Footprint" ""
			(at 346.71 53.34 0)
			(effects
				(font
					(size 1.27 1.27)
				)
				(hide yes)
			)
		)
		(property "Datasheet" ""
			(at 346.71 53.34 0)
			(effects
				(font
					(size 1.27 1.27)
				)
				(hide yes)
			)
		)
		(property "Description" ""
			(at 346.71 53.34 0)
			(effects
				(font
					(size 1.27 1.27)
				)
				(hide yes)
			)
		)
		(pin "1"
		)
		(instances
			(project "com-express-7-baseboard"
				(path ""
					(reference "#FLG012")
					(unit 1)
				)
			)
		)
	)
	(symbol
		(lib_id "antmicroTransistorsFETsMOSFETsSingle:SI7613DN-T1-GE3")
		(at 99.06 231.14 270)
		(mirror x)
		(unit 1)
		(exclude_from_sim no)
		(in_bom yes)
		(on_board yes)
		(dnp no)
		(property "Reference" "Q2"
			(at 101.6 215.9 90)
			(effects
				(font
					(size 1.27 1.27)
					(thickness 0.15)
				)
			)
		)
		(property "Value" "SI7613DN-T1-GE3"
			(at 101.6 218.44 90)
			(effects
				(font
					(size 1.27 1.27)
					(thickness 0.15)
				)
				(hide yes)
			)
		)
		(property "Footprint" "antmicro-footprints:Vishay_PowerPAK_1212-8_Single"
			(at 100.33 215.9 0)
			(effects
				(font
					(size 1.27 1.27)
					(thickness 0.15)
				)
				(justify left bottom)
				(hide yes)
			)
		)
		(property "Datasheet" "https://www.vishay.com/docs/64809/si7613dn.pdf"
			(at 97.79 215.9 0)
			(effects
				(font
					(size 1.27 1.27)
					(thickness 0.15)
				)
				(justify left bottom)
				(hide yes)
			)
		)
		(property "Description" ""
			(at 99.06 231.14 0)
			(effects
				(font
					(size 1.27 1.27)
				)
				(hide yes)
			)
		)
		(property "MPN" "SI7613DN-T1-GE3"
			(at 91.44 218.44 90)
			(effects
				(font
					(size 1.27 1.27)
					(thickness 0.15)
				)
				(justify left bottom)
			)
		)
		(property "Manufacturer" "Vishay"
			(at 91.44 215.9 0)
			(effects
				(font
					(size 1.27 1.27)
					(thickness 0.15)
				)
				(justify left bottom)
				(hide yes)
			)
		)
		(property "Author" "Antmicro"
			(at 88.9 215.9 0)
			(effects
				(font
					(size 1.27 1.27)
					(thickness 0.15)
				)
				(justify left bottom)
				(hide yes)
			)
		)
		(property "License" "Apache-2.0"
			(at 86.36 215.9 0)
			(effects
				(font
					(size 1.27 1.27)
					(thickness 0.15)
				)
				(justify left bottom)
				(hide yes)
			)
		)
		(pin "5"
		)
		(pin "4"
		)
		(pin "3"
		)
		(pin "1"
		)
		(pin "2"
		)
		(instances
			(project "com-express-7-baseboard"
				(path ""
					(reference "Q2")
					(unit 1)
				)
			)
		)
	)
	(symbol
		(lib_id "antmicropower:GND")
		(at 139.7 63.5 0)
		(mirror y)
		(unit 1)
		(exclude_from_sim no)
		(in_bom yes)
		(on_board yes)
		(dnp no)
		(property "Reference" "#PWR0110"
			(at 130.81 66.04 0)
			(effects
				(font
					(size 1.27 1.27)
					(thickness 0.15)
				)
				(justify left bottom)
				(hide yes)
			)
		)
		(property "Value" "GND"
			(at 139.7 67.31 0)
			(effects
				(font
					(size 1.27 1.27)
					(thickness 0.15)
				)
			)
		)
		(property "Footprint" ""
			(at 130.81 71.12 0)
			(effects
				(font
					(size 1.27 1.27)
					(thickness 0.15)
				)
				(justify left bottom)
				(hide yes)
			)
		)
		(property "Datasheet" ""
			(at 130.81 76.2 0)
			(effects
				(font
					(size 1.27 1.27)
					(thickness 0.15)
				)
				(justify left bottom)
				(hide yes)
			)
		)
		(property "Description" ""
			(at 139.7 63.5 0)
			(effects
				(font
					(size 1.27 1.27)
				)
				(hide yes)
			)
		)
		(property "Author" "Antmicro"
			(at 130.81 71.12 0)
			(effects
				(font
					(size 1.27 1.27)
					(thickness 0.15)
				)
				(justify left bottom)
				(hide yes)
			)
		)
		(property "License" "Apache-2.0"
			(at 130.81 73.66 0)
			(effects
				(font
					(size 1.27 1.27)
					(thickness 0.15)
				)
				(justify left bottom)
				(hide yes)
			)
		)
		(pin "1"
		)
		(instances
			(project "com-express-7-baseboard"
				(path ""
					(reference "#PWR0110")
					(unit 1)
				)
			)
		)
	)
	(symbol
		(lib_id "antmicroCapacitors0402:C_1u_0402")
		(at 334.01 226.06 90)
		(unit 1)
		(exclude_from_sim no)
		(in_bom yes)
		(on_board yes)
		(dnp no)
		(fields_autoplaced yes)
		(property "Reference" "C66"
			(at 336.55 222.2435 90)
			(effects
				(font
					(size 1.27 1.27)
					(thickness 0.15)
				)
				(justify right)
			)
		)
		(property "Value" "C_1u_0402"
			(at 344.17 205.74 0)
			(effects
				(font
					(size 1.27 1.27)
					(thickness 0.15)
				)
				(justify left bottom)
				(hide yes)
			)
		)
		(property "Footprint" "antmicro-footprints:C_0402_1005Metric"
			(at 346.71 205.74 0)
			(effects
				(font
					(size 1.27 1.27)
					(thickness 0.15)
				)
				(justify left bottom)
				(hide yes)
			)
		)
		(property "Datasheet" "https://product.tdk.com/en/search/capacitor/ceramic/mlcc/info?part_no=C1005X6S1A105K050BC"
			(at 349.25 205.74 0)
			(effects
				(font
					(size 1.27 1.27)
					(thickness 0.15)
				)
				(justify left bottom)
				(hide yes)
			)
		)
		(property "Description" ""
			(at 334.01 226.06 0)
			(effects
				(font
					(size 1.27 1.27)
				)
				(hide yes)
			)
		)
		(property "MPN" "C1005X6S1A105K050BC"
			(at 351.79 205.74 0)
			(effects
				(font
					(size 1.27 1.27)
					(thickness 0.15)
				)
				(justify left bottom)
				(hide yes)
			)
		)
		(property "Manufacturer" "TDK"
			(at 354.33 205.74 0)
			(effects
				(font
					(size 1.27 1.27)
					(thickness 0.15)
				)
				(justify left bottom)
				(hide yes)
			)
		)
		(property "License" "Apache-2.0"
			(at 356.87 205.74 0)
			(effects
				(font
					(size 1.27 1.27)
					(thickness 0.15)
				)
				(justify left bottom)
				(hide yes)
			)
		)
		(property "Author" "Antmicro"
			(at 359.41 205.74 0)
			(effects
				(font
					(size 1.27 1.27)
					(thickness 0.15)
				)
				(justify left bottom)
				(hide yes)
			)
		)
		(property "Val" "1u"
			(at 336.55 224.7835 90)
			(effects
				(font
					(size 1.27 1.27)
					(thickness 0.15)
				)
				(justify right)
			)
		)
		(property "Voltage" ""
			(at 361.95 205.74 0)
			(effects
				(font
					(size 1.27 1.27)
				)
				(justify left bottom)
				(hide yes)
			)
		)
		(property "Dielectric" ""
			(at 364.49 205.74 0)
			(effects
				(font
					(size 1.27 1.27)
				)
				(justify left bottom)
				(hide yes)
			)
		)
		(property "Public" "False"
			(at 367.03 205.74 0)
			(effects
				(font
					(size 1.27 1.27)
				)
				(justify left bottom)
				(hide yes)
			)
		)
		(pin "1"
		)
		(pin "2"
		)
		(instances
			(project "com-express-7-baseboard"
				(path ""
					(reference "C66")
					(unit 1)
				)
			)
		)
	)
	(symbol
		(lib_id "antmicropower:GND")
		(at 237.49 59.69 0)
		(unit 1)
		(exclude_from_sim no)
		(in_bom yes)
		(on_board yes)
		(dnp no)
		(property "Reference" "#PWR0129"
			(at 246.38 62.23 0)
			(effects
				(font
					(size 1.27 1.27)
					(thickness 0.15)
				)
				(justify left bottom)
				(hide yes)
			)
		)
		(property "Value" "GND"
			(at 237.49 63.5 0)
			(effects
				(font
					(size 1.27 1.27)
					(thickness 0.15)
				)
			)
		)
		(property "Footprint" ""
			(at 246.38 67.31 0)
			(effects
				(font
					(size 1.27 1.27)
					(thickness 0.15)
				)
				(justify left bottom)
				(hide yes)
			)
		)
		(property "Datasheet" ""
			(at 246.38 72.39 0)
			(effects
				(font
					(size 1.27 1.27)
					(thickness 0.15)
				)
				(justify left bottom)
				(hide yes)
			)
		)
		(property "Description" ""
			(at 237.49 59.69 0)
			(effects
				(font
					(size 1.27 1.27)
				)
				(hide yes)
			)
		)
		(property "Author" "Antmicro"
			(at 246.38 67.31 0)
			(effects
				(font
					(size 1.27 1.27)
					(thickness 0.15)
				)
				(justify left bottom)
				(hide yes)
			)
		)
		(property "License" "Apache-2.0"
			(at 246.38 69.85 0)
			(effects
				(font
					(size 1.27 1.27)
					(thickness 0.15)
				)
				(justify left bottom)
				(hide yes)
			)
		)
		(pin "1"
		)
		(instances
			(project "com-express-7-baseboard"
				(path ""
					(reference "#PWR0129")
					(unit 1)
				)
			)
		)
	)
	(symbol
		(lib_id "antmicroResistors0402:R_5k1_0402")
		(at 261.62 257.81 0)
		(unit 1)
		(exclude_from_sim no)
		(in_bom yes)
		(on_board yes)
		(dnp no)
		(property "Reference" "R328"
			(at 259.08 256.54 0)
			(effects
				(font
					(size 1.27 1.27)
					(thickness 0.15)
				)
			)
		)
		(property "Value" "R_5k1_0402"
			(at 281.94 270.51 0)
			(effects
				(font
					(size 1.27 1.27)
					(thickness 0.15)
				)
				(justify left bottom)
				(hide yes)
			)
		)
		(property "Footprint" "antmicro-footprints:R_0402_1005Metric"
			(at 281.94 273.05 0)
			(effects
				(font
					(size 1.27 1.27)
					(thickness 0.15)
				)
				(justify left bottom)
				(hide yes)
			)
		)
		(property "Datasheet" "https://www.bourns.com/docs/product-datasheets/cr.pdf"
			(at 281.94 275.59 0)
			(effects
				(font
					(size 1.27 1.27)
					(thickness 0.15)
				)
				(justify left bottom)
				(hide yes)
			)
		)
		(property "Description" ""
			(at 261.62 257.81 0)
			(effects
				(font
					(size 1.27 1.27)
				)
				(hide yes)
			)
		)
		(property "MPN" "CR0402-FX-5101GLF"
			(at 281.94 278.13 0)
			(effects
				(font
					(size 1.27 1.27)
					(thickness 0.15)
				)
				(justify left bottom)
				(hide yes)
			)
		)
		(property "Manufacturer" "Bourns"
			(at 281.94 280.67 0)
			(effects
				(font
					(size 1.27 1.27)
					(thickness 0.15)
				)
				(justify left bottom)
				(hide yes)
			)
		)
		(property "License" "Apache-2.0"
			(at 281.94 283.21 0)
			(effects
				(font
					(size 1.27 1.27)
					(thickness 0.15)
				)
				(justify left bottom)
				(hide yes)
			)
		)
		(property "Author" "Antmicro"
			(at 281.94 285.75 0)
			(effects
				(font
					(size 1.27 1.27)
					(thickness 0.15)
				)
				(justify left bottom)
				(hide yes)
			)
		)
		(property "Val" "5k1"
			(at 267.97 256.54 0)
			(effects
				(font
					(size 1.27 1.27)
					(thickness 0.15)
				)
			)
		)
		(property "Tolerance" "1%"
			(at 281.94 267.97 0)
			(effects
				(font
					(size 1.27 1.27)
				)
				(justify left bottom)
				(hide yes)
			)
		)
		(pin "2"
		)
		(pin "1"
		)
		(instances
			(project "com-express-7-baseboard"
				(path ""
					(reference "R328")
					(unit 1)
				)
			)
		)
	)
	(symbol
		(lib_id "antmicroTransistorsFETsMOSFETsSingle:BSS138-7-F")
		(at 91.44 246.38 0)
		(unit 1)
		(exclude_from_sim no)
		(in_bom yes)
		(on_board yes)
		(dnp no)
		(property "Reference" "Q1"
			(at 102.87 242.57 0)
			(effects
				(font
					(size 1.27 1.27)
					(thickness 0.15)
				)
				(justify left)
			)
		)
		(property "Value" "BSS138-7-F"
			(at 102.87 245.11 0)
			(effects
				(font
					(size 1.27 1.27)
					(thickness 0.15)
				)
				(justify left)
				(hide yes)
			)
		)
		(property "Footprint" "antmicro-footprints:SOT-23-3"
			(at 114.3 254 0)
			(effects
				(font
					(size 1.27 1.27)
					(thickness 0.15)
				)
				(justify left bottom)
				(hide yes)
			)
		)
		(property "Datasheet" "https://www.diodes.com/assets/Datasheets/ds30144.pdf"
			(at 114.3 256.54 0)
			(effects
				(font
					(size 1.27 1.27)
					(thickness 0.15)
				)
				(justify left bottom)
				(hide yes)
			)
		)
		(property "Description" ""
			(at 91.44 246.38 0)
			(effects
				(font
					(size 1.27 1.27)
				)
				(hide yes)
			)
		)
		(property "MPN" "BSS138-7-F"
			(at 102.87 246.38 0)
			(effects
				(font
					(size 1.27 1.27)
					(thickness 0.15)
				)
				(justify left bottom)
			)
		)
		(property "Manufacturer" "Diodes Incorporated"
			(at 114.3 261.62 0)
			(effects
				(font
					(size 1.27 1.27)
					(thickness 0.15)
				)
				(justify left bottom)
				(hide yes)
			)
		)
		(property "Author" "Antmicro"
			(at 114.3 264.16 0)
			(effects
				(font
					(size 1.27 1.27)
					(thickness 0.15)
				)
				(justify left bottom)
				(hide yes)
			)
		)
		(property "License" "Apache-2.0"
			(at 114.3 266.7 0)
			(effects
				(font
					(size 1.27 1.27)
					(thickness 0.15)
				)
				(justify left bottom)
				(hide yes)
			)
		)
		(pin "1"
		)
		(pin "2"
		)
		(pin "3"
		)
		(instances
			(project "com-express-7-baseboard"
				(path ""
					(reference "Q1")
					(unit 1)
				)
			)
		)
	)
	(symbol
		(lib_id "antmicropower:GND")
		(at 160.02 63.5 0)
		(unit 1)
		(exclude_from_sim no)
		(in_bom yes)
		(on_board yes)
		(dnp no)
		(property "Reference" "#PWR0115"
			(at 168.91 66.04 0)
			(effects
				(font
					(size 1.27 1.27)
					(thickness 0.15)
				)
				(justify left bottom)
				(hide yes)
			)
		)
		(property "Value" "GND"
			(at 160.02 67.31 0)
			(effects
				(font
					(size 1.27 1.27)
					(thickness 0.15)
				)
			)
		)
		(property "Footprint" ""
			(at 168.91 71.12 0)
			(effects
				(font
					(size 1.27 1.27)
					(thickness 0.15)
				)
				(justify left bottom)
				(hide yes)
			)
		)
		(property "Datasheet" ""
			(at 168.91 76.2 0)
			(effects
				(font
					(size 1.27 1.27)
					(thickness 0.15)
				)
				(justify left bottom)
				(hide yes)
			)
		)
		(property "Description" ""
			(at 160.02 63.5 0)
			(effects
				(font
					(size 1.27 1.27)
				)
				(hide yes)
			)
		)
		(property "Author" "Antmicro"
			(at 168.91 71.12 0)
			(effects
				(font
					(size 1.27 1.27)
					(thickness 0.15)
				)
				(justify left bottom)
				(hide yes)
			)
		)
		(property "License" "Apache-2.0"
			(at 168.91 73.66 0)
			(effects
				(font
					(size 1.27 1.27)
					(thickness 0.15)
				)
				(justify left bottom)
				(hide yes)
			)
		)
		(pin "1"
		)
		(instances
			(project "com-express-7-baseboard"
				(path ""
					(reference "#PWR0115")
					(unit 1)
				)
			)
		)
	)
	(symbol
		(lib_id "antmicroTestPoints:TP_0.75mm_SMD")
		(at 257.81 251.46 0)
		(mirror x)
		(unit 1)
		(exclude_from_sim no)
		(in_bom no)
		(on_board yes)
		(dnp no)
		(property "Reference" "TP99"
			(at 261.62 251.46 0)
			(effects
				(font
					(size 1.27 1.27)
					(thickness 0.15)
				)
				(justify left)
			)
		)
		(property "Value" "TP_0.75mm_SMD"
			(at 268.605 247.65 0)
			(effects
				(font
					(size 1.27 1.27)
					(thickness 0.15)
				)
				(justify left bottom)
				(hide yes)
			)
		)
		(property "Footprint" "antmicro-footprints:TP_SMD_0.75mm"
			(at 268.605 245.11 0)
			(effects
				(font
					(size 1.27 1.27)
					(thickness 0.15)
				)
				(justify left bottom)
				(hide yes)
			)
		)
		(property "Datasheet" ""
			(at 275.59 238.76 0)
			(effects
				(font
					(size 1.27 1.27)
					(thickness 0.15)
				)
				(justify left bottom)
				(hide yes)
			)
		)
		(property "Description" ""
			(at 257.81 251.46 0)
			(effects
				(font
					(size 1.27 1.27)
				)
				(hide yes)
			)
		)
		(property "MPN" ""
			(at 268.605 240.03 0)
			(effects
				(font
					(size 1.27 1.27)
					(thickness 0.15)
				)
				(justify left bottom)
				(hide yes)
			)
		)
		(property "Manufacturer" ""
			(at 268.605 245.11 0)
			(effects
				(font
					(size 1.27 1.27)
					(thickness 0.15)
				)
				(justify left bottom)
				(hide yes)
			)
		)
		(property "Author" "Antmicro"
			(at 268.605 242.57 0)
			(effects
				(font
					(size 1.27 1.27)
					(thickness 0.15)
				)
				(justify left bottom)
				(hide yes)
			)
		)
		(property "License" "Apache-2.0"
			(at 268.605 240.03 0)
			(effects
				(font
					(size 1.27 1.27)
					(thickness 0.15)
				)
				(justify left bottom)
				(hide yes)
			)
		)
		(property "Public" "False"
			(at 267.97 237.49 0)
			(effects
				(font
					(size 1.27 1.27)
				)
				(justify left bottom)
				(hide yes)
			)
		)
		(pin "1"
		)
		(instances
			(project "com-express-7-baseboard"
				(path ""
					(reference "TP99")
					(unit 1)
				)
			)
		)
	)
	(symbol
		(lib_id "antmicropower:+12V_AON")
		(at 228.6 50.8 0)
		(unit 1)
		(exclude_from_sim no)
		(in_bom yes)
		(on_board yes)
		(dnp no)
		(fields_autoplaced yes)
		(property "Reference" "#PWR0127"
			(at 228.6 54.61 0)
			(effects
				(font
					(size 1.27 1.27)
				)
				(hide yes)
			)
		)
		(property "Value" "+12V_AON"
			(at 228.6 45.72 0)
			(effects
				(font
					(size 1.27 1.27)
				)
			)
		)
		(property "Footprint" ""
			(at 228.6 50.8 0)
			(effects
				(font
					(size 1.27 1.27)
				)
				(hide yes)
			)
		)
		(property "Datasheet" ""
			(at 228.6 50.8 0)
			(effects
				(font
					(size 1.27 1.27)
				)
				(hide yes)
			)
		)
		(property "Description" ""
			(at 228.6 50.8 0)
			(effects
				(font
					(size 1.27 1.27)
				)
				(hide yes)
			)
		)
		(pin "1"
		)
		(instances
			(project "com-express-7-baseboard"
				(path ""
					(reference "#PWR0127")
					(unit 1)
				)
			)
		)
	)
	(symbol
		(lib_id "antmicroTransistorsFETsMOSFETsSingle:SI7613DN-T1-GE3")
		(at 377.19 63.5 270)
		(mirror x)
		(unit 1)
		(exclude_from_sim no)
		(in_bom yes)
		(on_board yes)
		(dnp no)
		(property "Reference" "Q4"
			(at 379.73 49.53 90)
			(effects
				(font
					(size 1.27 1.27)
					(thickness 0.15)
				)
			)
		)
		(property "Value" "SI7613DN-T1-GE3"
			(at 379.73 50.8 90)
			(effects
				(font
					(size 1.27 1.27)
					(thickness 0.15)
				)
				(hide yes)
			)
		)
		(property "Footprint" "antmicro-footprints:Vishay_PowerPAK_1212-8_Single"
			(at 378.46 48.26 0)
			(effects
				(font
					(size 1.27 1.27)
					(thickness 0.15)
				)
				(justify left bottom)
				(hide yes)
			)
		)
		(property "Datasheet" "https://www.vishay.com/docs/64809/si7613dn.pdf"
			(at 375.92 48.26 0)
			(effects
				(font
					(size 1.27 1.27)
					(thickness 0.15)
				)
				(justify left bottom)
				(hide yes)
			)
		)
		(property "Description" ""
			(at 377.19 63.5 0)
			(effects
				(font
					(size 1.27 1.27)
				)
				(hide yes)
			)
		)
		(property "MPN" "SI7613DN-T1-GE3"
			(at 379.73 52.07 90)
			(effects
				(font
					(size 1.27 1.27)
					(thickness 0.15)
				)
			)
		)
		(property "Manufacturer" "Vishay"
			(at 369.57 48.26 0)
			(effects
				(font
					(size 1.27 1.27)
					(thickness 0.15)
				)
				(justify left bottom)
				(hide yes)
			)
		)
		(property "Author" "Antmicro"
			(at 367.03 48.26 0)
			(effects
				(font
					(size 1.27 1.27)
					(thickness 0.15)
				)
				(justify left bottom)
				(hide yes)
			)
		)
		(property "License" "Apache-2.0"
			(at 364.49 48.26 0)
			(effects
				(font
					(size 1.27 1.27)
					(thickness 0.15)
				)
				(justify left bottom)
				(hide yes)
			)
		)
		(pin "5"
		)
		(pin "4"
		)
		(pin "3"
		)
		(pin "1"
		)
		(pin "2"
		)
		(instances
			(project "com-express-7-baseboard"
				(path ""
					(reference "Q4")
					(unit 1)
				)
			)
		)
	)
	(symbol
		(lib_id "antmicroPowerMeasurement:INA219AIDCNR")
		(at 323.85 73.66 0)
		(unit 1)
		(exclude_from_sim no)
		(in_bom yes)
		(on_board yes)
		(dnp no)
		(property "Reference" "U50"
			(at 331.47 68.58 0)
			(effects
				(font
					(size 1.27 1.27)
				)
			)
		)
		(property "Value" "INA219AIDCNR"
			(at 323.85 73.66 0)
			(effects
				(font
					(size 1.27 1.27)
				)
				(hide yes)
			)
		)
		(property "Footprint" "antmicro-footprints:SOT-23-8"
			(at 323.85 73.66 0)
			(effects
				(font
					(size 1.27 1.27)
				)
				(hide yes)
			)
		)
		(property "Datasheet" "https://www.ti.com/lit/ds/symlink/ina219.pdf?ts=1713856455637&ref_url=https%253A%252F%252Fwww.mouser.es%252F"
			(at 323.85 73.66 0)
			(effects
				(font
					(size 1.27 1.27)
				)
				(hide yes)
			)
		)
		(property "Description" ""
			(at 323.85 73.66 0)
			(effects
				(font
					(size 1.27 1.27)
				)
				(hide yes)
			)
		)
		(property "Manufacturer" "Texas Instruments"
			(at 323.85 73.66 0)
			(effects
				(font
					(size 1.27 1.27)
				)
				(hide yes)
			)
		)
		(property "MPN" "INA219AIDCNR"
			(at 331.47 71.12 0)
			(effects
				(font
					(size 1.27 1.27)
				)
			)
		)
		(property "Author" "Antmicro"
			(at 349.25 93.98 0)
			(effects
				(font
					(size 1.27 1.27)
					(thickness 0.15)
				)
				(justify left bottom)
				(hide yes)
			)
		)
		(property "License" "Apache-2.0"
			(at 349.25 96.52 0)
			(effects
				(font
					(size 1.27 1.27)
					(thickness 0.15)
				)
				(justify left bottom)
				(hide yes)
			)
		)
		(pin "1"
		)
		(pin "2"
		)
		(pin "5"
		)
		(pin "6"
		)
		(pin "8"
		)
		(pin "3"
		)
		(pin "7"
		)
		(pin "4"
		)
		(instances
			(project "com-express-7-baseboard"
				(path ""
					(reference "U50")
					(unit 1)
				)
			)
		)
	)
	(symbol
		(lib_id "antmicroDCDCConverters:TPS564247DRLR")
		(at 260.35 55.88 0)
		(unit 1)
		(exclude_from_sim no)
		(in_bom yes)
		(on_board yes)
		(dnp no)
		(fields_autoplaced yes)
		(property "Reference" "U21"
			(at 267.97 49.53 0)
			(effects
				(font
					(size 1.27 1.27)
				)
			)
		)
		(property "Value" "TPS564247DRLR"
			(at 260.35 55.88 0)
			(effects
				(font
					(size 1.27 1.27)
				)
				(hide yes)
			)
		)
		(property "Footprint" "antmicro-footprints:SOT-563"
			(at 260.35 55.88 0)
			(effects
				(font
					(size 1.27 1.27)
				)
				(hide yes)
			)
		)
		(property "Datasheet" "https://www.ti.com/lit/ds/symlink/tps564247.pdf?ts=1713526387938&ref_url=https%253A%252F%252Fwww.mouser.pl%252F"
			(at 260.35 55.88 0)
			(effects
				(font
					(size 1.27 1.27)
				)
				(hide yes)
			)
		)
		(property "Description" ""
			(at 260.35 55.88 0)
			(effects
				(font
					(size 1.27 1.27)
				)
				(hide yes)
			)
		)
		(property "MPN" "TPS564247DRLR"
			(at 267.97 52.07 0)
			(effects
				(font
					(size 1.27 1.27)
				)
			)
		)
		(property "Author" "Antmicro"
			(at 290.83 76.2 0)
			(effects
				(font
					(size 1.27 1.27)
					(thickness 0.15)
				)
				(justify left bottom)
				(hide yes)
			)
		)
		(property "License" "Apache-2.0"
			(at 290.83 78.74 0)
			(effects
				(font
					(size 1.27 1.27)
					(thickness 0.15)
				)
				(justify left bottom)
				(hide yes)
			)
		)
		(property "Manufacturer" "Texas Instruments"
			(at 290.83 73.66 0)
			(effects
				(font
					(size 1.27 1.27)
					(thickness 0.15)
				)
				(justify left bottom)
				(hide yes)
			)
		)
		(pin "1"
		)
		(pin "6"
		)
		(pin "3"
		)
		(pin "2"
		)
		(pin "5"
		)
		(pin "4"
		)
		(instances
			(project "com-express-7-baseboard"
				(path ""
					(reference "U21")
					(unit 1)
				)
			)
		)
	)
	(symbol
		(lib_id "antmicroTestPoints:TP_0.75mm_SMD")
		(at 257.81 254 0)
		(mirror x)
		(unit 1)
		(exclude_from_sim no)
		(in_bom no)
		(on_board yes)
		(dnp no)
		(property "Reference" "TP100"
			(at 261.62 254 0)
			(effects
				(font
					(size 1.27 1.27)
					(thickness 0.15)
				)
				(justify left)
			)
		)
		(property "Value" "TP_0.75mm_SMD"
			(at 268.605 250.19 0)
			(effects
				(font
					(size 1.27 1.27)
					(thickness 0.15)
				)
				(justify left bottom)
				(hide yes)
			)
		)
		(property "Footprint" "antmicro-footprints:TP_SMD_0.75mm"
			(at 268.605 247.65 0)
			(effects
				(font
					(size 1.27 1.27)
					(thickness 0.15)
				)
				(justify left bottom)
				(hide yes)
			)
		)
		(property "Datasheet" ""
			(at 275.59 241.3 0)
			(effects
				(font
					(size 1.27 1.27)
					(thickness 0.15)
				)
				(justify left bottom)
				(hide yes)
			)
		)
		(property "Description" ""
			(at 257.81 254 0)
			(effects
				(font
					(size 1.27 1.27)
				)
				(hide yes)
			)
		)
		(property "MPN" ""
			(at 268.605 242.57 0)
			(effects
				(font
					(size 1.27 1.27)
					(thickness 0.15)
				)
				(justify left bottom)
				(hide yes)
			)
		)
		(property "Manufacturer" ""
			(at 268.605 247.65 0)
			(effects
				(font
					(size 1.27 1.27)
					(thickness 0.15)
				)
				(justify left bottom)
				(hide yes)
			)
		)
		(property "Author" "Antmicro"
			(at 268.605 245.11 0)
			(effects
				(font
					(size 1.27 1.27)
					(thickness 0.15)
				)
				(justify left bottom)
				(hide yes)
			)
		)
		(property "License" "Apache-2.0"
			(at 268.605 242.57 0)
			(effects
				(font
					(size 1.27 1.27)
					(thickness 0.15)
				)
				(justify left bottom)
				(hide yes)
			)
		)
		(property "Public" "False"
			(at 267.97 240.03 0)
			(effects
				(font
					(size 1.27 1.27)
				)
				(justify left bottom)
				(hide yes)
			)
		)
		(pin "1"
		)
		(instances
			(project "com-express-7-baseboard"
				(path ""
					(reference "TP100")
					(unit 1)
				)
			)
		)
	)
	(symbol
		(lib_id "antmicroCapacitors0402:C_100n_0402")
		(at 189.23 161.29 90)
		(unit 1)
		(exclude_from_sim no)
		(in_bom yes)
		(on_board yes)
		(dnp no)
		(fields_autoplaced yes)
		(property "Reference" "C204"
			(at 191.77 157.4735 90)
			(effects
				(font
					(size 1.27 1.27)
					(thickness 0.15)
				)
				(justify right)
			)
		)
		(property "Value" "C_100n_0402"
			(at 199.39 140.97 0)
			(effects
				(font
					(size 1.27 1.27)
					(thickness 0.15)
				)
				(justify left bottom)
				(hide yes)
			)
		)
		(property "Footprint" "antmicro-footprints:C_0402_1005Metric"
			(at 201.93 140.97 0)
			(effects
				(font
					(size 1.27 1.27)
					(thickness 0.15)
				)
				(justify left bottom)
				(hide yes)
			)
		)
		(property "Datasheet" "https://www.murata.com/products/productdetail?partno=GRM155R61H104KE14%23"
			(at 204.47 140.97 0)
			(effects
				(font
					(size 1.27 1.27)
					(thickness 0.15)
				)
				(justify left bottom)
				(hide yes)
			)
		)
		(property "Description" ""
			(at 189.23 161.29 0)
			(effects
				(font
					(size 1.27 1.27)
				)
				(hide yes)
			)
		)
		(property "MPN" "GRM155R61H104KE14D"
			(at 207.01 140.97 0)
			(effects
				(font
					(size 1.27 1.27)
					(thickness 0.15)
				)
				(justify left bottom)
				(hide yes)
			)
		)
		(property "Manufacturer" "Murata"
			(at 209.55 140.97 0)
			(effects
				(font
					(size 1.27 1.27)
					(thickness 0.15)
				)
				(justify left bottom)
				(hide yes)
			)
		)
		(property "License" "Apache-2.0"
			(at 212.09 140.97 0)
			(effects
				(font
					(size 1.27 1.27)
					(thickness 0.15)
				)
				(justify left bottom)
				(hide yes)
			)
		)
		(property "Author" "Antmicro"
			(at 214.63 140.97 0)
			(effects
				(font
					(size 1.27 1.27)
					(thickness 0.15)
				)
				(justify left bottom)
				(hide yes)
			)
		)
		(property "Val" "100n"
			(at 191.77 160.0135 90)
			(effects
				(font
					(size 1.27 1.27)
					(thickness 0.15)
				)
				(justify right)
			)
		)
		(property "Voltage" "50V"
			(at 217.17 140.97 0)
			(effects
				(font
					(size 1.27 1.27)
				)
				(justify left bottom)
				(hide yes)
			)
		)
		(property "Dielectric" "X5R"
			(at 219.71 140.97 0)
			(effects
				(font
					(size 1.27 1.27)
				)
				(justify left bottom)
				(hide yes)
			)
		)
		(property "Public" "False"
			(at 222.25 140.97 0)
			(effects
				(font
					(size 1.27 1.27)
				)
				(justify left bottom)
				(hide yes)
			)
		)
		(pin "1"
		)
		(pin "2"
		)
		(instances
			(project "com-express-7-baseboard"
				(path ""
					(reference "C204")
					(unit 1)
				)
			)
		)
	)
	(symbol
		(lib_id "antmicroPowerMeasurement:INA219AIDCNR")
		(at 172.72 149.86 0)
		(unit 1)
		(exclude_from_sim no)
		(in_bom yes)
		(on_board yes)
		(dnp no)
		(property "Reference" "U49"
			(at 179.07 144.78 0)
			(effects
				(font
					(size 1.27 1.27)
				)
			)
		)
		(property "Value" "INA219AIDCNR"
			(at 172.72 149.86 0)
			(effects
				(font
					(size 1.27 1.27)
				)
				(hide yes)
			)
		)
		(property "Footprint" "antmicro-footprints:SOT-23-8"
			(at 172.72 149.86 0)
			(effects
				(font
					(size 1.27 1.27)
				)
				(hide yes)
			)
		)
		(property "Datasheet" "https://www.ti.com/lit/ds/symlink/ina219.pdf?ts=1713856455637&ref_url=https%253A%252F%252Fwww.mouser.es%252F"
			(at 172.72 149.86 0)
			(effects
				(font
					(size 1.27 1.27)
				)
				(hide yes)
			)
		)
		(property "Description" ""
			(at 172.72 149.86 0)
			(effects
				(font
					(size 1.27 1.27)
				)
				(hide yes)
			)
		)
		(property "Manufacturer" "Texas Instruments"
			(at 172.72 149.86 0)
			(effects
				(font
					(size 1.27 1.27)
				)
				(hide yes)
			)
		)
		(property "MPN" "INA219AIDCNR"
			(at 179.07 147.32 0)
			(effects
				(font
					(size 1.27 1.27)
				)
			)
		)
		(property "Author" "Antmicro"
			(at 198.12 170.18 0)
			(effects
				(font
					(size 1.27 1.27)
					(thickness 0.15)
				)
				(justify left bottom)
				(hide yes)
			)
		)
		(property "License" "Apache-2.0"
			(at 198.12 172.72 0)
			(effects
				(font
					(size 1.27 1.27)
					(thickness 0.15)
				)
				(justify left bottom)
				(hide yes)
			)
		)
		(pin "1"
		)
		(pin "2"
		)
		(pin "5"
		)
		(pin "6"
		)
		(pin "8"
		)
		(pin "3"
		)
		(pin "7"
		)
		(pin "4"
		)
		(instances
			(project "com-express-7-baseboard"
				(path ""
					(reference "U49")
					(unit 1)
				)
			)
		)
	)
	(symbol
		(lib_id "antmicropower:GND")
		(at 149.86 143.51 0)
		(unit 1)
		(exclude_from_sim no)
		(in_bom yes)
		(on_board yes)
		(dnp no)
		(property "Reference" "#PWR0113"
			(at 158.75 146.05 0)
			(effects
				(font
					(size 1.27 1.27)
					(thickness 0.15)
				)
				(justify left bottom)
				(hide yes)
			)
		)
		(property "Value" "GND"
			(at 149.86 147.32 0)
			(effects
				(font
					(size 1.27 1.27)
					(thickness 0.15)
				)
			)
		)
		(property "Footprint" ""
			(at 158.75 151.13 0)
			(effects
				(font
					(size 1.27 1.27)
					(thickness 0.15)
				)
				(justify left bottom)
				(hide yes)
			)
		)
		(property "Datasheet" ""
			(at 158.75 156.21 0)
			(effects
				(font
					(size 1.27 1.27)
					(thickness 0.15)
				)
				(justify left bottom)
				(hide yes)
			)
		)
		(property "Description" ""
			(at 149.86 143.51 0)
			(effects
				(font
					(size 1.27 1.27)
				)
				(hide yes)
			)
		)
		(property "Author" "Antmicro"
			(at 158.75 151.13 0)
			(effects
				(font
					(size 1.27 1.27)
					(thickness 0.15)
				)
				(justify left bottom)
				(hide yes)
			)
		)
		(property "License" "Apache-2.0"
			(at 158.75 153.67 0)
			(effects
				(font
					(size 1.27 1.27)
					(thickness 0.15)
				)
				(justify left bottom)
				(hide yes)
			)
		)
		(pin "1"
		)
		(instances
			(project "com-express-7-baseboard"
				(path ""
					(reference "#PWR0113")
					(unit 1)
				)
			)
		)
	)
	(symbol
		(lib_id "antmicropower:+3V3_AON")
		(at 163.83 226.06 0)
		(unit 1)
		(exclude_from_sim no)
		(in_bom yes)
		(on_board yes)
		(dnp no)
		(fields_autoplaced yes)
		(property "Reference" "#PWR0118"
			(at 163.83 229.87 0)
			(effects
				(font
					(size 1.27 1.27)
				)
				(hide yes)
			)
		)
		(property "Value" "+3V3_AON"
			(at 163.83 220.98 0)
			(effects
				(font
					(size 1.27 1.27)
				)
			)
		)
		(property "Footprint" ""
			(at 163.83 226.06 0)
			(effects
				(font
					(size 1.27 1.27)
				)
				(hide yes)
			)
		)
		(property "Datasheet" ""
			(at 163.83 226.06 0)
			(effects
				(font
					(size 1.27 1.27)
				)
				(hide yes)
			)
		)
		(property "Description" ""
			(at 163.83 226.06 0)
			(effects
				(font
					(size 1.27 1.27)
				)
				(hide yes)
			)
		)
		(pin "1"
		)
		(instances
			(project "com-express-7-baseboard"
				(path ""
					(reference "#PWR0118")
					(unit 1)
				)
			)
		)
	)
	(symbol
		(lib_id "antmicropower:GND")
		(at 83.82 154.94 0)
		(mirror y)
		(unit 1)
		(exclude_from_sim no)
		(in_bom yes)
		(on_board yes)
		(dnp no)
		(property "Reference" "#PWR099"
			(at 74.93 157.48 0)
			(effects
				(font
					(size 1.27 1.27)
					(thickness 0.15)
				)
				(justify left bottom)
				(hide yes)
			)
		)
		(property "Value" "GND"
			(at 83.82 158.75 0)
			(effects
				(font
					(size 1.27 1.27)
					(thickness 0.15)
				)
			)
		)
		(property "Footprint" ""
			(at 74.93 162.56 0)
			(effects
				(font
					(size 1.27 1.27)
					(thickness 0.15)
				)
				(justify left bottom)
				(hide yes)
			)
		)
		(property "Datasheet" ""
			(at 74.93 167.64 0)
			(effects
				(font
					(size 1.27 1.27)
					(thickness 0.15)
				)
				(justify left bottom)
				(hide yes)
			)
		)
		(property "Description" ""
			(at 83.82 154.94 0)
			(effects
				(font
					(size 1.27 1.27)
				)
				(hide yes)
			)
		)
		(property "Author" "Antmicro"
			(at 74.93 162.56 0)
			(effects
				(font
					(size 1.27 1.27)
					(thickness 0.15)
				)
				(justify left bottom)
				(hide yes)
			)
		)
		(property "License" "Apache-2.0"
			(at 74.93 165.1 0)
			(effects
				(font
					(size 1.27 1.27)
					(thickness 0.15)
				)
				(justify left bottom)
				(hide yes)
			)
		)
		(pin "1"
		)
		(instances
			(project "com-express-7-baseboard"
				(path ""
					(reference "#PWR099")
					(unit 1)
				)
			)
		)
	)
	(symbol
		(lib_id "antmicropower:GND")
		(at 34.29 227.33 0)
		(mirror y)
		(unit 1)
		(exclude_from_sim no)
		(in_bom yes)
		(on_board yes)
		(dnp no)
		(property "Reference" "#PWR087"
			(at 25.4 229.87 0)
			(effects
				(font
					(size 1.27 1.27)
					(thickness 0.15)
				)
				(justify left bottom)
				(hide yes)
			)
		)
		(property "Value" "GND"
			(at 34.29 231.14 0)
			(effects
				(font
					(size 1.27 1.27)
					(thickness 0.15)
				)
			)
		)
		(property "Footprint" ""
			(at 25.4 234.95 0)
			(effects
				(font
					(size 1.27 1.27)
					(thickness 0.15)
				)
				(justify left bottom)
				(hide yes)
			)
		)
		(property "Datasheet" ""
			(at 25.4 240.03 0)
			(effects
				(font
					(size 1.27 1.27)
					(thickness 0.15)
				)
				(justify left bottom)
				(hide yes)
			)
		)
		(property "Description" ""
			(at 34.29 227.33 0)
			(effects
				(font
					(size 1.27 1.27)
				)
				(hide yes)
			)
		)
		(property "Author" "Antmicro"
			(at 25.4 234.95 0)
			(effects
				(font
					(size 1.27 1.27)
					(thickness 0.15)
				)
				(justify left bottom)
				(hide yes)
			)
		)
		(property "License" "Apache-2.0"
			(at 25.4 237.49 0)
			(effects
				(font
					(size 1.27 1.27)
					(thickness 0.15)
				)
				(justify left bottom)
				(hide yes)
			)
		)
		(pin "1"
		)
		(instances
			(project "com-express-7-baseboard"
				(path ""
					(reference "#PWR087")
					(unit 1)
				)
			)
		)
	)
	(symbol
		(lib_id "antmicroResistors0402:R_10k_0402")
		(at 139.7 55.88 90)
		(unit 1)
		(exclude_from_sim no)
		(in_bom yes)
		(on_board yes)
		(dnp no)
		(fields_autoplaced yes)
		(property "Reference" "R97"
			(at 142.24 52.0699 90)
			(effects
				(font
					(size 1.27 1.27)
					(thickness 0.15)
				)
				(justify right)
			)
		)
		(property "Value" "R_10k_0402"
			(at 152.4 35.56 0)
			(effects
				(font
					(size 1.27 1.27)
					(thickness 0.15)
				)
				(justify left bottom)
				(hide yes)
			)
		)
		(property "Footprint" "antmicro-footprints:R_0402_1005Metric"
			(at 154.94 35.56 0)
			(effects
				(font
					(size 1.27 1.27)
					(thickness 0.15)
				)
				(justify left bottom)
				(hide yes)
			)
		)
		(property "Datasheet" "https://www.bourns.com/docs/product-datasheets/cr.pdf"
			(at 157.48 35.56 0)
			(effects
				(font
					(size 1.27 1.27)
					(thickness 0.15)
				)
				(justify left bottom)
				(hide yes)
			)
		)
		(property "Description" ""
			(at 139.7 55.88 0)
			(effects
				(font
					(size 1.27 1.27)
				)
				(hide yes)
			)
		)
		(property "MPN" "CR0402-FX-1002GLF"
			(at 160.02 35.56 0)
			(effects
				(font
					(size 1.27 1.27)
					(thickness 0.15)
				)
				(justify left bottom)
				(hide yes)
			)
		)
		(property "Manufacturer" "Bourns"
			(at 162.56 35.56 0)
			(effects
				(font
					(size 1.27 1.27)
					(thickness 0.15)
				)
				(justify left bottom)
				(hide yes)
			)
		)
		(property "License" "Apache-2.0"
			(at 165.1 35.56 0)
			(effects
				(font
					(size 1.27 1.27)
					(thickness 0.15)
				)
				(justify left bottom)
				(hide yes)
			)
		)
		(property "Author" "Antmicro"
			(at 167.64 35.56 0)
			(effects
				(font
					(size 1.27 1.27)
					(thickness 0.15)
				)
				(justify left bottom)
				(hide yes)
			)
		)
		(property "Val" "10k"
			(at 142.24 54.6099 90)
			(effects
				(font
					(size 1.27 1.27)
					(thickness 0.15)
				)
				(justify right)
			)
		)
		(property "Tolerance" "1%"
			(at 149.86 35.56 0)
			(effects
				(font
					(size 1.27 1.27)
				)
				(justify left bottom)
				(hide yes)
			)
		)
		(property "Public" "False"
			(at 170.18 35.56 0)
			(effects
				(font
					(size 1.27 1.27)
				)
				(justify left bottom)
				(hide yes)
			)
		)
		(pin "1"
		)
		(pin "2"
		)
		(instances
			(project "com-express-7-baseboard"
				(path ""
					(reference "R97")
					(unit 1)
				)
			)
		)
	)
	(symbol
		(lib_id "antmicroCapacitorspol:C_Pol_68u_16V_Panasonic-TQC-D")
		(at 48.26 127 270)
		(unit 1)
		(exclude_from_sim no)
		(in_bom yes)
		(on_board yes)
		(dnp no)
		(fields_autoplaced yes)
		(property "Reference" "C39"
			(at 50.8 126.4665 90)
			(effects
				(font
					(size 1.27 1.27)
					(thickness 0.15)
				)
				(justify left)
			)
		)
		(property "Value" "C_Pol_68u_16V_Panasonic-TQC-D"
			(at 38.1 142.24 0)
			(effects
				(font
					(size 1.27 1.27)
					(thickness 0.15)
				)
				(justify left bottom)
				(hide yes)
			)
		)
		(property "Footprint" "antmicro-footprints:C_Pol_EIA-D"
			(at 35.56 142.24 0)
			(effects
				(font
					(size 1.27 1.27)
					(thickness 0.15)
				)
				(justify left bottom)
				(hide yes)
			)
		)
		(property "Datasheet" "https://industrial.panasonic.com/sa/products/pt/aluminum-cap-smd/models/16TQC68MYF"
			(at 33.02 142.24 0)
			(effects
				(font
					(size 1.27 1.27)
					(thickness 0.15)
				)
				(justify left bottom)
				(hide yes)
			)
		)
		(property "Description" ""
			(at 48.26 127 0)
			(effects
				(font
					(size 1.27 1.27)
				)
				(hide yes)
			)
		)
		(property "Author" "Antmicro"
			(at 30.48 142.24 0)
			(effects
				(font
					(size 1.27 1.27)
					(thickness 0.15)
				)
				(justify left bottom)
				(hide yes)
			)
		)
		(property "License" "Apache-2.0"
			(at 27.94 142.24 0)
			(effects
				(font
					(size 1.27 1.27)
					(thickness 0.15)
				)
				(justify left bottom)
				(hide yes)
			)
		)
		(property "MPN" "16TQC68MYF"
			(at 25.4 142.24 0)
			(effects
				(font
					(size 1.27 1.27)
					(thickness 0.15)
				)
				(justify left bottom)
				(hide yes)
			)
		)
		(property "Manufacturer" "Panasonic"
			(at 22.86 142.24 0)
			(effects
				(font
					(size 1.27 1.27)
					(thickness 0.15)
				)
				(justify left bottom)
				(hide yes)
			)
		)
		(property "Val" "68u"
			(at 50.8 129.0065 90)
			(effects
				(font
					(size 1.27 1.27)
					(thickness 0.15)
				)
				(justify left)
			)
		)
		(property "Voltage" "16V"
			(at 50.8 131.5465 90)
			(effects
				(font
					(size 1.27 1.27)
					(thickness 0.15)
				)
				(justify left)
			)
		)
		(property "Dielectric" "template_dielectric"
			(at 22.86 140.97 0)
			(effects
				(font
					(size 1.27 1.27)
				)
				(justify left bottom)
				(hide yes)
			)
		)
		(property "Public" "False"
			(at 20.32 140.97 0)
			(effects
				(font
					(size 1.27 1.27)
				)
				(justify left bottom)
				(hide yes)
			)
		)
		(pin "1"
		)
		(pin "2"
		)
		(instances
			(project "com-express-7-baseboard"
				(path ""
					(reference "C39")
					(unit 1)
				)
			)
		)
	)
	(symbol
		(lib_id "antmicropower:GND")
		(at 322.58 88.9 0)
		(unit 1)
		(exclude_from_sim no)
		(in_bom yes)
		(on_board yes)
		(dnp no)
		(property "Reference" "#PWR0444"
			(at 331.47 91.44 0)
			(effects
				(font
					(size 1.27 1.27)
					(thickness 0.15)
				)
				(justify left bottom)
				(hide yes)
			)
		)
		(property "Value" "GND"
			(at 322.58 92.71 0)
			(effects
				(font
					(size 1.27 1.27)
					(thickness 0.15)
				)
			)
		)
		(property "Footprint" ""
			(at 331.47 96.52 0)
			(effects
				(font
					(size 1.27 1.27)
					(thickness 0.15)
				)
				(justify left bottom)
				(hide yes)
			)
		)
		(property "Datasheet" ""
			(at 331.47 101.6 0)
			(effects
				(font
					(size 1.27 1.27)
					(thickness 0.15)
				)
				(justify left bottom)
				(hide yes)
			)
		)
		(property "Description" ""
			(at 322.58 88.9 0)
			(effects
				(font
					(size 1.27 1.27)
				)
				(hide yes)
			)
		)
		(property "Author" "Antmicro"
			(at 331.47 96.52 0)
			(effects
				(font
					(size 1.27 1.27)
					(thickness 0.15)
				)
				(justify left bottom)
				(hide yes)
			)
		)
		(property "License" "Apache-2.0"
			(at 331.47 99.06 0)
			(effects
				(font
					(size 1.27 1.27)
					(thickness 0.15)
				)
				(justify left bottom)
				(hide yes)
			)
		)
		(pin "1"
		)
		(instances
			(project "com-express-7-baseboard"
				(path ""
					(reference "#PWR0444")
					(unit 1)
				)
			)
		)
	)
	(symbol
		(lib_id "antmicroLEDIndicationDiscrete:LED_G_0603_LTST-C190GKT")
		(at 280.67 243.84 270)
		(mirror x)
		(unit 1)
		(exclude_from_sim no)
		(in_bom yes)
		(on_board yes)
		(dnp no)
		(property "Reference" "D26"
			(at 281.305 239.395 90)
			(effects
				(font
					(size 1.27 1.27)
				)
				(justify left)
			)
		)
		(property "Value" "LED_G_0603_LTST-C190GKT"
			(at 273.05 220.98 0)
			(effects
				(font
					(size 1.27 1.27)
					(thickness 0.15)
				)
				(justify left bottom)
				(hide yes)
			)
		)
		(property "Footprint" "antmicro-footprints:LED_0603_1608Metric_G"
			(at 270.51 220.98 0)
			(effects
				(font
					(size 1.27 1.27)
					(thickness 0.15)
				)
				(justify left bottom)
				(hide yes)
			)
		)
		(property "Datasheet" "https://media.digikey.com/pdf/Data%20Sheets/Lite-On%20PDFs/LTST-C190GKT.pdf"
			(at 267.97 220.98 0)
			(effects
				(font
					(size 1.27 1.27)
					(thickness 0.15)
				)
				(justify left bottom)
				(hide yes)
			)
		)
		(property "Description" ""
			(at 280.67 243.84 0)
			(effects
				(font
					(size 1.27 1.27)
				)
				(hide yes)
			)
		)
		(property "MPN" "LTST-C190GKT"
			(at 284.48 238.7601 90)
			(effects
				(font
					(size 1.27 1.27)
					(thickness 0.15)
				)
				(justify left)
				(hide yes)
			)
		)
		(property "Manufacturer" "Lite-On"
			(at 262.89 220.98 0)
			(effects
				(font
					(size 1.27 1.27)
					(thickness 0.15)
				)
				(justify left bottom)
				(hide yes)
			)
		)
		(property "Author" "Antmicro"
			(at 260.35 220.98 0)
			(effects
				(font
					(size 1.27 1.27)
					(thickness 0.15)
				)
				(justify left bottom)
				(hide yes)
			)
		)
		(property "License" "Apache-2.0"
			(at 257.81 220.98 0)
			(effects
				(font
					(size 1.27 1.27)
					(thickness 0.15)
				)
				(justify left bottom)
				(hide yes)
			)
		)
		(property "Public" "False"
			(at 262.89 223.52 0)
			(effects
				(font
					(size 1.27 1.27)
				)
				(justify left bottom)
				(hide yes)
			)
		)
		(property "Color" "Green"
			(at 281.305 243.84 90)
			(effects
				(font
					(size 1.27 1.27)
				)
				(justify left)
			)
		)
		(pin "1"
		)
		(pin "2"
		)
		(instances
			(project "com-express-7-baseboard"
				(path ""
					(reference "D26")
					(unit 1)
				)
			)
		)
	)
	(symbol
		(lib_id "antmicroDCDCConverters:TPS56C230")
		(at 105.41 44.45 0)
		(unit 1)
		(exclude_from_sim no)
		(in_bom yes)
		(on_board yes)
		(dnp no)
		(fields_autoplaced yes)
		(property "Reference" "U18"
			(at 114.3 36.83 0)
			(effects
				(font
					(size 1.27 1.27)
					(thickness 0.15)
				)
			)
		)
		(property "Value" "TPS56C230"
			(at 114.3 39.37 0)
			(effects
				(font
					(size 1.27 1.27)
					(thickness 0.15)
				)
				(hide yes)
			)
		)
		(property "Footprint" "antmicro-footprints:QFN-20-1EP_3x3mm_P0.45mm_TPS56xxxx"
			(at 138.43 52.07 0)
			(effects
				(font
					(size 1.27 1.27)
					(thickness 0.15)
				)
				(justify left bottom)
				(hide yes)
			)
		)
		(property "Datasheet" "https://www.ti.com/lit/ds/symlink/tps56c230.pdf?ts=1672843259715&ref_url=https%253A%252F%252Fwww.ti.com%252Fproduct%252FTPS56C230"
			(at 138.43 54.61 0)
			(effects
				(font
					(size 1.27 1.27)
					(thickness 0.15)
				)
				(justify left bottom)
				(hide yes)
			)
		)
		(property "Description" ""
			(at 105.41 44.45 0)
			(effects
				(font
					(size 1.27 1.27)
				)
				(hide yes)
			)
		)
		(property "Manufacturer" "Texas Instruments"
			(at 138.43 57.15 0)
			(effects
				(font
					(size 1.27 1.27)
					(thickness 0.15)
				)
				(justify left bottom)
				(hide yes)
			)
		)
		(property "MPN" "TPS56C230RJER"
			(at 114.3 39.37 0)
			(effects
				(font
					(size 1.27 1.27)
					(thickness 0.15)
				)
			)
		)
		(property "Author" "Antmicro"
			(at 138.43 62.23 0)
			(effects
				(font
					(size 1.27 1.27)
					(thickness 0.15)
				)
				(justify left bottom)
				(hide yes)
			)
		)
		(property "License" "Apache-2.0"
			(at 138.43 64.77 0)
			(effects
				(font
					(size 1.27 1.27)
					(thickness 0.15)
				)
				(justify left bottom)
				(hide yes)
			)
		)
		(pin "20"
		)
		(pin "2"
		)
		(pin "21"
		)
		(pin "17"
		)
		(pin "19"
		)
		(pin "6"
		)
		(pin "18"
		)
		(pin "8"
		)
		(pin "9"
		)
		(pin "3"
		)
		(pin "13"
		)
		(pin "12"
		)
		(pin "4"
		)
		(pin "16"
		)
		(pin "14"
		)
		(pin "11"
		)
		(pin "15"
		)
		(pin "5"
		)
		(pin "10"
		)
		(pin "7"
		)
		(pin "1"
		)
		(instances
			(project "com-express-7-baseboard"
				(path ""
					(reference "U18")
					(unit 1)
				)
			)
		)
	)
	(symbol
		(lib_id "antmicroResistors0402:R_10k_0402")
		(at 104.14 60.96 90)
		(unit 1)
		(exclude_from_sim no)
		(in_bom yes)
		(on_board yes)
		(dnp no)
		(property "Reference" "R95"
			(at 102.87 57.15 90)
			(effects
				(font
					(size 1.27 1.27)
					(thickness 0.15)
				)
				(justify left)
			)
		)
		(property "Value" "R_10k_0402"
			(at 116.84 40.64 0)
			(effects
				(font
					(size 1.27 1.27)
					(thickness 0.15)
				)
				(justify left bottom)
				(hide yes)
			)
		)
		(property "Footprint" "antmicro-footprints:R_0402_1005Metric"
			(at 119.38 40.64 0)
			(effects
				(font
					(size 1.27 1.27)
					(thickness 0.15)
				)
				(justify left bottom)
				(hide yes)
			)
		)
		(property "Datasheet" "https://www.bourns.com/docs/product-datasheets/cr.pdf"
			(at 121.92 40.64 0)
			(effects
				(font
					(size 1.27 1.27)
					(thickness 0.15)
				)
				(justify left bottom)
				(hide yes)
			)
		)
		(property "Description" ""
			(at 104.14 60.96 0)
			(effects
				(font
					(size 1.27 1.27)
				)
				(hide yes)
			)
		)
		(property "MPN" "CR0402-FX-1002GLF"
			(at 124.46 40.64 0)
			(effects
				(font
					(size 1.27 1.27)
					(thickness 0.15)
				)
				(justify left bottom)
				(hide yes)
			)
		)
		(property "Manufacturer" "Bourns"
			(at 127 40.64 0)
			(effects
				(font
					(size 1.27 1.27)
					(thickness 0.15)
				)
				(justify left bottom)
				(hide yes)
			)
		)
		(property "License" "Apache-2.0"
			(at 129.54 40.64 0)
			(effects
				(font
					(size 1.27 1.27)
					(thickness 0.15)
				)
				(justify left bottom)
				(hide yes)
			)
		)
		(property "Author" "Antmicro"
			(at 132.08 40.64 0)
			(effects
				(font
					(size 1.27 1.27)
					(thickness 0.15)
				)
				(justify left bottom)
				(hide yes)
			)
		)
		(property "Val" "10k"
			(at 102.87 59.69 90)
			(effects
				(font
					(size 1.27 1.27)
					(thickness 0.15)
				)
				(justify left)
			)
		)
		(property "Tolerance" "1%"
			(at 114.3 40.64 0)
			(effects
				(font
					(size 1.27 1.27)
				)
				(justify left bottom)
				(hide yes)
			)
		)
		(property "Public" "False"
			(at 134.62 40.64 0)
			(effects
				(font
					(size 1.27 1.27)
				)
				(justify left bottom)
				(hide yes)
			)
		)
		(pin "1"
		)
		(pin "2"
		)
		(instances
			(project "com-express-7-baseboard"
				(path ""
					(reference "R95")
					(unit 1)
				)
			)
		)
	)
	(symbol
		(lib_id "antmicropower:GND")
		(at 334.01 226.06 0)
		(unit 1)
		(exclude_from_sim no)
		(in_bom yes)
		(on_board yes)
		(dnp no)
		(property "Reference" "#PWR0143"
			(at 342.9 228.6 0)
			(effects
				(font
					(size 1.27 1.27)
					(thickness 0.15)
				)
				(justify left bottom)
				(hide yes)
			)
		)
		(property "Value" "GND"
			(at 334.01 229.87 0)
			(effects
				(font
					(size 1.27 1.27)
					(thickness 0.15)
				)
			)
		)
		(property "Footprint" ""
			(at 342.9 233.68 0)
			(effects
				(font
					(size 1.27 1.27)
					(thickness 0.15)
				)
				(justify left bottom)
				(hide yes)
			)
		)
		(property "Datasheet" ""
			(at 342.9 238.76 0)
			(effects
				(font
					(size 1.27 1.27)
					(thickness 0.15)
				)
				(justify left bottom)
				(hide yes)
			)
		)
		(property "Description" ""
			(at 334.01 226.06 0)
			(effects
				(font
					(size 1.27 1.27)
				)
				(hide yes)
			)
		)
		(property "Author" "Antmicro"
			(at 342.9 233.68 0)
			(effects
				(font
					(size 1.27 1.27)
					(thickness 0.15)
				)
				(justify left bottom)
				(hide yes)
			)
		)
		(property "License" "Apache-2.0"
			(at 342.9 236.22 0)
			(effects
				(font
					(size 1.27 1.27)
					(thickness 0.15)
				)
				(justify left bottom)
				(hide yes)
			)
		)
		(pin "1"
		)
		(instances
			(project "com-express-7-baseboard"
				(path ""
					(reference "#PWR0143")
					(unit 1)
				)
			)
		)
	)
	(symbol
		(lib_id "antmicroPMICPowerSequencers:TPS3840PL30DBVR")
		(at 173.99 240.03 0)
		(unit 1)
		(exclude_from_sim no)
		(in_bom yes)
		(on_board yes)
		(dnp no)
		(property "Reference" "U20"
			(at 182.88 233.68 0)
			(effects
				(font
					(size 1.27 1.27)
					(thickness 0.15)
				)
			)
		)
		(property "Value" "TPS3840PL30DBVR"
			(at 182.88 234.95 0)
			(effects
				(font
					(size 1.27 1.27)
					(thickness 0.15)
				)
				(hide yes)
			)
		)
		(property "Footprint" "antmicro-footprints:SOT-23-5"
			(at 212.09 246.38 0)
			(effects
				(font
					(size 1.27 1.27)
					(thickness 0.15)
				)
				(justify left bottom)
				(hide yes)
			)
		)
		(property "Datasheet" "https://www.ti.com/lit/ds/symlink/tps3840.pdf?HQS=dis-mous-null-mousermode-dsf-pf-null-wwe&DCM=yes&ref_url=https%3A%2F%2Fwww.mouser.com%2F&distId=26"
			(at 212.09 248.92 0)
			(effects
				(font
					(size 1.27 1.27)
					(thickness 0.15)
				)
				(justify left bottom)
				(hide yes)
			)
		)
		(property "Description" ""
			(at 173.99 240.03 0)
			(effects
				(font
					(size 1.27 1.27)
				)
				(hide yes)
			)
		)
		(property "Manufacturer" "Texas Instruments"
			(at 212.09 251.46 0)
			(effects
				(font
					(size 1.27 1.27)
					(thickness 0.15)
				)
				(justify left bottom)
				(hide yes)
			)
		)
		(property "MPN" "TPS3840PL30DBVR"
			(at 173.99 236.22 0)
			(effects
				(font
					(size 1.27 1.27)
					(thickness 0.15)
				)
				(justify left)
			)
		)
		(property "Author" "Antmicro"
			(at 212.09 256.54 0)
			(effects
				(font
					(size 1.27 1.27)
					(thickness 0.15)
				)
				(justify left bottom)
				(hide yes)
			)
		)
		(property "License" "Apache-2.0"
			(at 212.09 259.08 0)
			(effects
				(font
					(size 1.27 1.27)
					(thickness 0.15)
				)
				(justify left bottom)
				(hide yes)
			)
		)
		(pin "4"
		)
		(pin "5"
		)
		(pin "3"
		)
		(pin "1"
		)
		(pin "2"
		)
		(instances
			(project "com-express-7-baseboard"
				(path ""
					(reference "U20")
					(unit 1)
				)
			)
		)
	)
	(symbol
		(lib_id "antmicroCapacitors0402:C_1u_0402")
		(at 82.55 62.23 90)
		(unit 1)
		(exclude_from_sim no)
		(in_bom yes)
		(on_board yes)
		(dnp no)
		(fields_autoplaced yes)
		(property "Reference" "C44"
			(at 85.09 58.4135 90)
			(effects
				(font
					(size 1.27 1.27)
					(thickness 0.15)
				)
				(justify right)
			)
		)
		(property "Value" "C_1u_0402"
			(at 92.71 41.91 0)
			(effects
				(font
					(size 1.27 1.27)
					(thickness 0.15)
				)
				(justify left bottom)
				(hide yes)
			)
		)
		(property "Footprint" "antmicro-footprints:C_0402_1005Metric"
			(at 95.25 41.91 0)
			(effects
				(font
					(size 1.27 1.27)
					(thickness 0.15)
				)
				(justify left bottom)
				(hide yes)
			)
		)
		(property "Datasheet" "https://product.tdk.com/en/search/capacitor/ceramic/mlcc/info?part_no=C1005X6S1A105K050BC"
			(at 97.79 41.91 0)
			(effects
				(font
					(size 1.27 1.27)
					(thickness 0.15)
				)
				(justify left bottom)
				(hide yes)
			)
		)
		(property "Description" ""
			(at 82.55 62.23 0)
			(effects
				(font
					(size 1.27 1.27)
				)
				(hide yes)
			)
		)
		(property "MPN" "C1005X6S1A105K050BC"
			(at 100.33 41.91 0)
			(effects
				(font
					(size 1.27 1.27)
					(thickness 0.15)
				)
				(justify left bottom)
				(hide yes)
			)
		)
		(property "Manufacturer" "TDK"
			(at 102.87 41.91 0)
			(effects
				(font
					(size 1.27 1.27)
					(thickness 0.15)
				)
				(justify left bottom)
				(hide yes)
			)
		)
		(property "License" "Apache-2.0"
			(at 105.41 41.91 0)
			(effects
				(font
					(size 1.27 1.27)
					(thickness 0.15)
				)
				(justify left bottom)
				(hide yes)
			)
		)
		(property "Author" "Antmicro"
			(at 107.95 41.91 0)
			(effects
				(font
					(size 1.27 1.27)
					(thickness 0.15)
				)
				(justify left bottom)
				(hide yes)
			)
		)
		(property "Val" "1u"
			(at 85.09 60.9535 90)
			(effects
				(font
					(size 1.27 1.27)
					(thickness 0.15)
				)
				(justify right)
			)
		)
		(property "Voltage" ""
			(at 110.49 41.91 0)
			(effects
				(font
					(size 1.27 1.27)
				)
				(justify left bottom)
				(hide yes)
			)
		)
		(property "Dielectric" ""
			(at 113.03 41.91 0)
			(effects
				(font
					(size 1.27 1.27)
				)
				(justify left bottom)
				(hide yes)
			)
		)
		(property "Public" "False"
			(at 115.57 41.91 0)
			(effects
				(font
					(size 1.27 1.27)
				)
				(justify left bottom)
				(hide yes)
			)
		)
		(pin "1"
		)
		(pin "2"
		)
		(instances
			(project "com-express-7-baseboard"
				(path ""
					(reference "C44")
					(unit 1)
				)
			)
		)
	)
	(symbol
		(lib_id "antmicropower:GND")
		(at 259.08 67.31 0)
		(unit 1)
		(exclude_from_sim no)
		(in_bom yes)
		(on_board yes)
		(dnp no)
		(property "Reference" "#PWR0134"
			(at 267.97 69.85 0)
			(effects
				(font
					(size 1.27 1.27)
					(thickness 0.15)
				)
				(justify left bottom)
				(hide yes)
			)
		)
		(property "Value" "GND"
			(at 259.08 71.12 0)
			(effects
				(font
					(size 1.27 1.27)
					(thickness 0.15)
				)
			)
		)
		(property "Footprint" ""
			(at 267.97 74.93 0)
			(effects
				(font
					(size 1.27 1.27)
					(thickness 0.15)
				)
				(justify left bottom)
				(hide yes)
			)
		)
		(property "Datasheet" ""
			(at 267.97 80.01 0)
			(effects
				(font
					(size 1.27 1.27)
					(thickness 0.15)
				)
				(justify left bottom)
				(hide yes)
			)
		)
		(property "Description" ""
			(at 259.08 67.31 0)
			(effects
				(font
					(size 1.27 1.27)
				)
				(hide yes)
			)
		)
		(property "Author" "Antmicro"
			(at 267.97 74.93 0)
			(effects
				(font
					(size 1.27 1.27)
					(thickness 0.15)
				)
				(justify left bottom)
				(hide yes)
			)
		)
		(property "License" "Apache-2.0"
			(at 267.97 77.47 0)
			(effects
				(font
					(size 1.27 1.27)
					(thickness 0.15)
				)
				(justify left bottom)
				(hide yes)
			)
		)
		(pin "1"
		)
		(instances
			(project "com-express-7-baseboard"
				(path ""
					(reference "#PWR0134")
					(unit 1)
				)
			)
		)
	)
	(symbol
		(lib_id "antmicroResistors0402:R_10k_0402")
		(at 91.44 154.94 90)
		(unit 1)
		(exclude_from_sim no)
		(in_bom yes)
		(on_board yes)
		(dnp no)
		(fields_autoplaced yes)
		(property "Reference" "R92"
			(at 93.98 151.1299 90)
			(effects
				(font
					(size 1.27 1.27)
					(thickness 0.15)
				)
				(justify right)
			)
		)
		(property "Value" "R_10k_0402"
			(at 104.14 134.62 0)
			(effects
				(font
					(size 1.27 1.27)
					(thickness 0.15)
				)
				(justify left bottom)
				(hide yes)
			)
		)
		(property "Footprint" "antmicro-footprints:R_0402_1005Metric"
			(at 106.68 134.62 0)
			(effects
				(font
					(size 1.27 1.27)
					(thickness 0.15)
				)
				(justify left bottom)
				(hide yes)
			)
		)
		(property "Datasheet" "https://www.bourns.com/docs/product-datasheets/cr.pdf"
			(at 109.22 134.62 0)
			(effects
				(font
					(size 1.27 1.27)
					(thickness 0.15)
				)
				(justify left bottom)
				(hide yes)
			)
		)
		(property "Description" ""
			(at 91.44 154.94 0)
			(effects
				(font
					(size 1.27 1.27)
				)
				(hide yes)
			)
		)
		(property "MPN" "CR0402-FX-1002GLF"
			(at 111.76 134.62 0)
			(effects
				(font
					(size 1.27 1.27)
					(thickness 0.15)
				)
				(justify left bottom)
				(hide yes)
			)
		)
		(property "Manufacturer" "Bourns"
			(at 114.3 134.62 0)
			(effects
				(font
					(size 1.27 1.27)
					(thickness 0.15)
				)
				(justify left bottom)
				(hide yes)
			)
		)
		(property "License" "Apache-2.0"
			(at 116.84 134.62 0)
			(effects
				(font
					(size 1.27 1.27)
					(thickness 0.15)
				)
				(justify left bottom)
				(hide yes)
			)
		)
		(property "Author" "Antmicro"
			(at 119.38 134.62 0)
			(effects
				(font
					(size 1.27 1.27)
					(thickness 0.15)
				)
				(justify left bottom)
				(hide yes)
			)
		)
		(property "Val" "10k"
			(at 93.98 153.6699 90)
			(effects
				(font
					(size 1.27 1.27)
					(thickness 0.15)
				)
				(justify right)
			)
		)
		(property "Tolerance" "1%"
			(at 101.6 134.62 0)
			(effects
				(font
					(size 1.27 1.27)
				)
				(justify left bottom)
				(hide yes)
			)
		)
		(property "Public" "False"
			(at 121.92 134.62 0)
			(effects
				(font
					(size 1.27 1.27)
				)
				(justify left bottom)
				(hide yes)
			)
		)
		(pin "1"
		)
		(pin "2"
		)
		(instances
			(project "com-express-7-baseboard"
				(path ""
					(reference "R92")
					(unit 1)
				)
			)
		)
	)
	(symbol
		(lib_id "antmicropower:GND")
		(at 90.17 74.93 0)
		(mirror y)
		(unit 1)
		(exclude_from_sim no)
		(in_bom yes)
		(on_board yes)
		(dnp no)
		(property "Reference" "#PWR0101"
			(at 81.28 77.47 0)
			(effects
				(font
					(size 1.27 1.27)
					(thickness 0.15)
				)
				(justify left bottom)
				(hide yes)
			)
		)
		(property "Value" "GND"
			(at 90.17 78.74 0)
			(effects
				(font
					(size 1.27 1.27)
					(thickness 0.15)
				)
			)
		)
		(property "Footprint" ""
			(at 81.28 82.55 0)
			(effects
				(font
					(size 1.27 1.27)
					(thickness 0.15)
				)
				(justify left bottom)
				(hide yes)
			)
		)
		(property "Datasheet" ""
			(at 81.28 87.63 0)
			(effects
				(font
					(size 1.27 1.27)
					(thickness 0.15)
				)
				(justify left bottom)
				(hide yes)
			)
		)
		(property "Description" ""
			(at 90.17 74.93 0)
			(effects
				(font
					(size 1.27 1.27)
				)
				(hide yes)
			)
		)
		(property "Author" "Antmicro"
			(at 81.28 82.55 0)
			(effects
				(font
					(size 1.27 1.27)
					(thickness 0.15)
				)
				(justify left bottom)
				(hide yes)
			)
		)
		(property "License" "Apache-2.0"
			(at 81.28 85.09 0)
			(effects
				(font
					(size 1.27 1.27)
					(thickness 0.15)
				)
				(justify left bottom)
				(hide yes)
			)
		)
		(pin "1"
		)
		(instances
			(project "com-express-7-baseboard"
				(path ""
					(reference "#PWR0101")
					(unit 1)
				)
			)
		)
	)
	(symbol
		(lib_id "antmicropower:GND")
		(at 198.12 246.38 0)
		(mirror y)
		(unit 1)
		(exclude_from_sim no)
		(in_bom yes)
		(on_board yes)
		(dnp no)
		(property "Reference" "#PWR0126"
			(at 189.23 248.92 0)
			(effects
				(font
					(size 1.27 1.27)
					(thickness 0.15)
				)
				(justify left bottom)
				(hide yes)
			)
		)
		(property "Value" "GND"
			(at 198.12 250.19 0)
			(effects
				(font
					(size 1.27 1.27)
					(thickness 0.15)
				)
			)
		)
		(property "Footprint" ""
			(at 189.23 254 0)
			(effects
				(font
					(size 1.27 1.27)
					(thickness 0.15)
				)
				(justify left bottom)
				(hide yes)
			)
		)
		(property "Datasheet" ""
			(at 189.23 259.08 0)
			(effects
				(font
					(size 1.27 1.27)
					(thickness 0.15)
				)
				(justify left bottom)
				(hide yes)
			)
		)
		(property "Description" ""
			(at 198.12 246.38 0)
			(effects
				(font
					(size 1.27 1.27)
				)
				(hide yes)
			)
		)
		(property "Author" "Antmicro"
			(at 189.23 254 0)
			(effects
				(font
					(size 1.27 1.27)
					(thickness 0.15)
				)
				(justify left bottom)
				(hide yes)
			)
		)
		(property "License" "Apache-2.0"
			(at 189.23 256.54 0)
			(effects
				(font
					(size 1.27 1.27)
					(thickness 0.15)
				)
				(justify left bottom)
				(hide yes)
			)
		)
		(pin "1"
		)
		(instances
			(project "com-express-7-baseboard"
				(path ""
					(reference "#PWR0126")
					(unit 1)
				)
			)
		)
	)
	(symbol
		(lib_id "antmicroResistorsmisc:R_0R001_0805")
		(at 176.53 129.54 0)
		(unit 1)
		(exclude_from_sim no)
		(in_bom yes)
		(on_board yes)
		(dnp no)
		(property "Reference" "R104"
			(at 179.07 124.46 0)
			(effects
				(font
					(size 1.27 1.27)
					(thickness 0.15)
				)
			)
		)
		(property "Value" "R_0R001_0805"
			(at 196.85 142.24 0)
			(effects
				(font
					(size 1.27 1.27)
					(thickness 0.15)
				)
				(justify left bottom)
				(hide yes)
			)
		)
		(property "Footprint" "antmicro-footprints:R_0805_2012Metric"
			(at 196.85 144.78 0)
			(effects
				(font
					(size 1.27 1.27)
					(thickness 0.15)
				)
				(justify left bottom)
				(hide yes)
			)
		)
		(property "Datasheet" "https://www.eaton.com/content/dam/eaton/products/electronic-components/resources/data-sheet/eaton-msma-automotive-smd-current-sense-resistor-metal-strip-data-sheet-elx1179.pdf"
			(at 196.85 147.32 0)
			(effects
				(font
					(size 1.27 1.27)
					(thickness 0.15)
				)
				(justify left bottom)
				(hide yes)
			)
		)
		(property "Description" ""
			(at 176.53 129.54 0)
			(effects
				(font
					(size 1.27 1.27)
				)
				(hide yes)
			)
		)
		(property "MPN" "MSMA0805R0010FSM"
			(at 196.85 149.86 0)
			(effects
				(font
					(size 1.27 1.27)
					(thickness 0.15)
				)
				(justify left bottom)
				(hide yes)
			)
		)
		(property "Manufacturer" "Eaton"
			(at 196.85 152.4 0)
			(effects
				(font
					(size 1.27 1.27)
					(thickness 0.15)
				)
				(justify left bottom)
				(hide yes)
			)
		)
		(property "License" "Apache-2.0"
			(at 196.85 154.94 0)
			(effects
				(font
					(size 1.27 1.27)
					(thickness 0.15)
				)
				(justify left bottom)
				(hide yes)
			)
		)
		(property "Author" "Antmicro"
			(at 196.85 157.48 0)
			(effects
				(font
					(size 1.27 1.27)
					(thickness 0.15)
				)
				(justify left bottom)
				(hide yes)
			)
		)
		(property "Val" "0R001"
			(at 179.07 127 0)
			(effects
				(font
					(size 1.27 1.27)
					(thickness 0.15)
				)
			)
		)
		(property "Tolerance" "1%"
			(at 196.85 139.7 0)
			(effects
				(font
					(size 1.27 1.27)
				)
				(justify left bottom)
				(hide yes)
			)
		)
		(property "Public" "False"
			(at 196.85 160.02 0)
			(effects
				(font
					(size 1.27 1.27)
				)
				(justify left bottom)
				(hide yes)
			)
		)
		(pin "2"
		)
		(pin "1"
		)
		(instances
			(project "com-express-7-baseboard"
				(path ""
					(reference "R104")
					(unit 1)
				)
			)
		)
	)
	(symbol
		(lib_id "antmicropower:GND")
		(at 189.23 163.83 0)
		(unit 1)
		(exclude_from_sim no)
		(in_bom yes)
		(on_board yes)
		(dnp no)
		(property "Reference" "#PWR0442"
			(at 198.12 166.37 0)
			(effects
				(font
					(size 1.27 1.27)
					(thickness 0.15)
				)
				(justify left bottom)
				(hide yes)
			)
		)
		(property "Value" "GND"
			(at 189.23 167.64 0)
			(effects
				(font
					(size 1.27 1.27)
					(thickness 0.15)
				)
			)
		)
		(property "Footprint" ""
			(at 198.12 171.45 0)
			(effects
				(font
					(size 1.27 1.27)
					(thickness 0.15)
				)
				(justify left bottom)
				(hide yes)
			)
		)
		(property "Datasheet" ""
			(at 198.12 176.53 0)
			(effects
				(font
					(size 1.27 1.27)
					(thickness 0.15)
				)
				(justify left bottom)
				(hide yes)
			)
		)
		(property "Description" ""
			(at 189.23 163.83 0)
			(effects
				(font
					(size 1.27 1.27)
				)
				(hide yes)
			)
		)
		(property "Author" "Antmicro"
			(at 198.12 171.45 0)
			(effects
				(font
					(size 1.27 1.27)
					(thickness 0.15)
				)
				(justify left bottom)
				(hide yes)
			)
		)
		(property "License" "Apache-2.0"
			(at 198.12 173.99 0)
			(effects
				(font
					(size 1.27 1.27)
					(thickness 0.15)
				)
				(justify left bottom)
				(hide yes)
			)
		)
		(pin "1"
		)
		(instances
			(project "com-express-7-baseboard"
				(path ""
					(reference "#PWR0442")
					(unit 1)
				)
			)
		)
	)
	(symbol
		(lib_id "antmicropower:GND")
		(at 77.47 52.07 0)
		(mirror y)
		(unit 1)
		(exclude_from_sim no)
		(in_bom yes)
		(on_board yes)
		(dnp no)
		(property "Reference" "#PWR094"
			(at 68.58 54.61 0)
			(effects
				(font
					(size 1.27 1.27)
					(thickness 0.15)
				)
				(justify left bottom)
				(hide yes)
			)
		)
		(property "Value" "GND"
			(at 77.47 55.88 0)
			(effects
				(font
					(size 1.27 1.27)
					(thickness 0.15)
				)
			)
		)
		(property "Footprint" ""
			(at 68.58 59.69 0)
			(effects
				(font
					(size 1.27 1.27)
					(thickness 0.15)
				)
				(justify left bottom)
				(hide yes)
			)
		)
		(property "Datasheet" ""
			(at 68.58 64.77 0)
			(effects
				(font
					(size 1.27 1.27)
					(thickness 0.15)
				)
				(justify left bottom)
				(hide yes)
			)
		)
		(property "Description" ""
			(at 77.47 52.07 0)
			(effects
				(font
					(size 1.27 1.27)
				)
				(hide yes)
			)
		)
		(property "Author" "Antmicro"
			(at 68.58 59.69 0)
			(effects
				(font
					(size 1.27 1.27)
					(thickness 0.15)
				)
				(justify left bottom)
				(hide yes)
			)
		)
		(property "License" "Apache-2.0"
			(at 68.58 62.23 0)
			(effects
				(font
					(size 1.27 1.27)
					(thickness 0.15)
				)
				(justify left bottom)
				(hide yes)
			)
		)
		(pin "1"
		)
		(instances
			(project "com-express-7-baseboard"
				(path ""
					(reference "#PWR094")
					(unit 1)
				)
			)
		)
	)
	(symbol
		(lib_id "antmicroResistors0402:R_220R_0402")
		(at 236.22 269.24 90)
		(unit 1)
		(exclude_from_sim no)
		(in_bom yes)
		(on_board yes)
		(dnp no)
		(property "Reference" "R320"
			(at 237.49 265.43 90)
			(effects
				(font
					(size 1.27 1.27)
					(thickness 0.15)
				)
				(justify right)
			)
		)
		(property "Value" "R_220R_0402"
			(at 248.92 248.92 0)
			(effects
				(font
					(size 1.27 1.27)
					(thickness 0.15)
				)
				(justify left bottom)
				(hide yes)
			)
		)
		(property "Footprint" "antmicro-footprints:R_0402_1005Metric"
			(at 251.46 248.92 0)
			(effects
				(font
					(size 1.27 1.27)
					(thickness 0.15)
				)
				(justify left bottom)
				(hide yes)
			)
		)
		(property "Datasheet" "https://www.bourns.com/docs/product-datasheets/cr.pdf"
			(at 254 248.92 0)
			(effects
				(font
					(size 1.27 1.27)
					(thickness 0.15)
				)
				(justify left bottom)
				(hide yes)
			)
		)
		(property "Description" ""
			(at 236.22 269.24 0)
			(effects
				(font
					(size 1.27 1.27)
				)
				(hide yes)
			)
		)
		(property "MPN" "CR0402-FX-2200GLF"
			(at 256.54 248.92 0)
			(effects
				(font
					(size 1.27 1.27)
					(thickness 0.15)
				)
				(justify left bottom)
				(hide yes)
			)
		)
		(property "Manufacturer" "Bourns"
			(at 259.08 248.92 0)
			(effects
				(font
					(size 1.27 1.27)
					(thickness 0.15)
				)
				(justify left bottom)
				(hide yes)
			)
		)
		(property "License" "Apache-2.0"
			(at 261.62 248.92 0)
			(effects
				(font
					(size 1.27 1.27)
					(thickness 0.15)
				)
				(justify left bottom)
				(hide yes)
			)
		)
		(property "Author" "Antmicro"
			(at 264.16 248.92 0)
			(effects
				(font
					(size 1.27 1.27)
					(thickness 0.15)
				)
				(justify left bottom)
				(hide yes)
			)
		)
		(property "Val" "220R"
			(at 237.49 267.97 90)
			(effects
				(font
					(size 1.27 1.27)
					(thickness 0.15)
				)
				(justify right)
			)
		)
		(property "Tolerance" "1%"
			(at 246.38 248.92 0)
			(effects
				(font
					(size 1.27 1.27)
				)
				(justify left bottom)
				(hide yes)
			)
		)
		(property "Public" "False"
			(at 266.7 248.92 0)
			(effects
				(font
					(size 1.27 1.27)
				)
				(justify left bottom)
				(hide yes)
			)
		)
		(pin "2"
		)
		(pin "1"
		)
		(instances
			(project "com-express-7-baseboard"
				(path ""
					(reference "R320")
					(unit 1)
				)
			)
		)
	)
	(symbol
		(lib_id "antmicroResistors0402:R_10k_0402")
		(at 365.76 78.74 180)
		(unit 1)
		(exclude_from_sim no)
		(in_bom yes)
		(on_board yes)
		(dnp no)
		(property "Reference" "R116"
			(at 358.14 77.47 0)
			(effects
				(font
					(size 1.27 1.27)
					(thickness 0.15)
				)
			)
		)
		(property "Value" "R_10k_0402"
			(at 345.44 66.04 0)
			(effects
				(font
					(size 1.27 1.27)
					(thickness 0.15)
				)
				(justify left bottom)
				(hide yes)
			)
		)
		(property "Footprint" "antmicro-footprints:R_0402_1005Metric"
			(at 345.44 63.5 0)
			(effects
				(font
					(size 1.27 1.27)
					(thickness 0.15)
				)
				(justify left bottom)
				(hide yes)
			)
		)
		(property "Datasheet" "https://www.bourns.com/docs/product-datasheets/cr.pdf"
			(at 345.44 60.96 0)
			(effects
				(font
					(size 1.27 1.27)
					(thickness 0.15)
				)
				(justify left bottom)
				(hide yes)
			)
		)
		(property "Description" ""
			(at 365.76 78.74 0)
			(effects
				(font
					(size 1.27 1.27)
				)
				(hide yes)
			)
		)
		(property "MPN" "CR0402-FX-1002GLF"
			(at 345.44 58.42 0)
			(effects
				(font
					(size 1.27 1.27)
					(thickness 0.15)
				)
				(justify left bottom)
				(hide yes)
			)
		)
		(property "Manufacturer" "Bourns"
			(at 345.44 55.88 0)
			(effects
				(font
					(size 1.27 1.27)
					(thickness 0.15)
				)
				(justify left bottom)
				(hide yes)
			)
		)
		(property "License" "Apache-2.0"
			(at 345.44 53.34 0)
			(effects
				(font
					(size 1.27 1.27)
					(thickness 0.15)
				)
				(justify left bottom)
				(hide yes)
			)
		)
		(property "Author" "Antmicro"
			(at 345.44 50.8 0)
			(effects
				(font
					(size 1.27 1.27)
					(thickness 0.15)
				)
				(justify left bottom)
				(hide yes)
			)
		)
		(property "Val" "10k"
			(at 367.03 77.47 0)
			(effects
				(font
					(size 1.27 1.27)
					(thickness 0.15)
				)
			)
		)
		(property "Tolerance" "1%"
			(at 345.44 68.58 0)
			(effects
				(font
					(size 1.27 1.27)
				)
				(justify left bottom)
				(hide yes)
			)
		)
		(property "Public" "False"
			(at 345.44 48.26 0)
			(effects
				(font
					(size 1.27 1.27)
				)
				(justify left bottom)
				(hide yes)
			)
		)
		(pin "2"
		)
		(pin "1"
		)
		(instances
			(project "com-express-7-baseboard"
				(path ""
					(reference "R116")
					(unit 1)
				)
			)
		)
	)
	(symbol
		(lib_id "antmicropower:GND")
		(at 278.13 146.05 0)
		(unit 1)
		(exclude_from_sim no)
		(in_bom yes)
		(on_board yes)
		(dnp no)
		(property "Reference" "#PWR0135"
			(at 287.02 148.59 0)
			(effects
				(font
					(size 1.27 1.27)
					(thickness 0.15)
				)
				(justify left bottom)
				(hide yes)
			)
		)
		(property "Value" "GND"
			(at 278.13 149.86 0)
			(effects
				(font
					(size 1.27 1.27)
					(thickness 0.15)
				)
			)
		)
		(property "Footprint" ""
			(at 287.02 153.67 0)
			(effects
				(font
					(size 1.27 1.27)
					(thickness 0.15)
				)
				(justify left bottom)
				(hide yes)
			)
		)
		(property "Datasheet" ""
			(at 287.02 158.75 0)
			(effects
				(font
					(size 1.27 1.27)
					(thickness 0.15)
				)
				(justify left bottom)
				(hide yes)
			)
		)
		(property "Description" ""
			(at 278.13 146.05 0)
			(effects
				(font
					(size 1.27 1.27)
				)
				(hide yes)
			)
		)
		(property "Author" "Antmicro"
			(at 287.02 153.67 0)
			(effects
				(font
					(size 1.27 1.27)
					(thickness 0.15)
				)
				(justify left bottom)
				(hide yes)
			)
		)
		(property "License" "Apache-2.0"
			(at 287.02 156.21 0)
			(effects
				(font
					(size 1.27 1.27)
					(thickness 0.15)
				)
				(justify left bottom)
				(hide yes)
			)
		)
		(pin "1"
		)
		(instances
			(project "com-express-7-baseboard"
				(path ""
					(reference "#PWR0135")
					(unit 1)
				)
			)
		)
	)
	(symbol
		(lib_id "antmicroResistors0402:R_10k_0402")
		(at 104.14 140.97 90)
		(unit 1)
		(exclude_from_sim no)
		(in_bom yes)
		(on_board yes)
		(dnp no)
		(property "Reference" "R96"
			(at 102.87 137.16 90)
			(effects
				(font
					(size 1.27 1.27)
					(thickness 0.15)
				)
				(justify left)
			)
		)
		(property "Value" "R_10k_0402"
			(at 116.84 120.65 0)
			(effects
				(font
					(size 1.27 1.27)
					(thickness 0.15)
				)
				(justify left bottom)
				(hide yes)
			)
		)
		(property "Footprint" "antmicro-footprints:R_0402_1005Metric"
			(at 119.38 120.65 0)
			(effects
				(font
					(size 1.27 1.27)
					(thickness 0.15)
				)
				(justify left bottom)
				(hide yes)
			)
		)
		(property "Datasheet" "https://www.bourns.com/docs/product-datasheets/cr.pdf"
			(at 121.92 120.65 0)
			(effects
				(font
					(size 1.27 1.27)
					(thickness 0.15)
				)
				(justify left bottom)
				(hide yes)
			)
		)
		(property "Description" ""
			(at 104.14 140.97 0)
			(effects
				(font
					(size 1.27 1.27)
				)
				(hide yes)
			)
		)
		(property "MPN" "CR0402-FX-1002GLF"
			(at 124.46 120.65 0)
			(effects
				(font
					(size 1.27 1.27)
					(thickness 0.15)
				)
				(justify left bottom)
				(hide yes)
			)
		)
		(property "Manufacturer" "Bourns"
			(at 127 120.65 0)
			(effects
				(font
					(size 1.27 1.27)
					(thickness 0.15)
				)
				(justify left bottom)
				(hide yes)
			)
		)
		(property "License" "Apache-2.0"
			(at 129.54 120.65 0)
			(effects
				(font
					(size 1.27 1.27)
					(thickness 0.15)
				)
				(justify left bottom)
				(hide yes)
			)
		)
		(property "Author" "Antmicro"
			(at 132.08 120.65 0)
			(effects
				(font
					(size 1.27 1.27)
					(thickness 0.15)
				)
				(justify left bottom)
				(hide yes)
			)
		)
		(property "Val" "10k"
			(at 102.87 139.7 90)
			(effects
				(font
					(size 1.27 1.27)
					(thickness 0.15)
				)
				(justify left)
			)
		)
		(property "Tolerance" "1%"
			(at 114.3 120.65 0)
			(effects
				(font
					(size 1.27 1.27)
				)
				(justify left bottom)
				(hide yes)
			)
		)
		(property "Public" "False"
			(at 134.62 120.65 0)
			(effects
				(font
					(size 1.27 1.27)
				)
				(justify left bottom)
				(hide yes)
			)
		)
		(pin "1"
		)
		(pin "2"
		)
		(instances
			(project "com-express-7-baseboard"
				(path ""
					(reference "R96")
					(unit 1)
				)
			)
		)
	)
	(symbol
		(lib_id "antmicropower:GND")
		(at 116.84 231.14 0)
		(unit 1)
		(exclude_from_sim no)
		(in_bom yes)
		(on_board yes)
		(dnp no)
		(property "Reference" "#PWR0107"
			(at 125.73 233.68 0)
			(effects
				(font
					(size 1.27 1.27)
					(thickness 0.15)
				)
				(justify left bottom)
				(hide yes)
			)
		)
		(property "Value" "GND"
			(at 116.84 234.95 0)
			(effects
				(font
					(size 1.27 1.27)
					(thickness 0.15)
				)
			)
		)
		(property "Footprint" ""
			(at 125.73 238.76 0)
			(effects
				(font
					(size 1.27 1.27)
					(thickness 0.15)
				)
				(justify left bottom)
				(hide yes)
			)
		)
		(property "Datasheet" ""
			(at 125.73 243.84 0)
			(effects
				(font
					(size 1.27 1.27)
					(thickness 0.15)
				)
				(justify left bottom)
				(hide yes)
			)
		)
		(property "Description" ""
			(at 116.84 231.14 0)
			(effects
				(font
					(size 1.27 1.27)
				)
				(hide yes)
			)
		)
		(property "Author" "Antmicro"
			(at 125.73 238.76 0)
			(effects
				(font
					(size 1.27 1.27)
					(thickness 0.15)
				)
				(justify left bottom)
				(hide yes)
			)
		)
		(property "License" "Apache-2.0"
			(at 125.73 241.3 0)
			(effects
				(font
					(size 1.27 1.27)
					(thickness 0.15)
				)
				(justify left bottom)
				(hide yes)
			)
		)
		(pin "1"
		)
		(instances
			(project "com-express-7-baseboard"
				(path ""
					(reference "#PWR0107")
					(unit 1)
				)
			)
		)
	)
	(symbol
		(lib_id "antmicroPMICVoltageRegulatorsLinear:TLV73333PDBVT")
		(at 345.44 219.71 0)
		(unit 1)
		(exclude_from_sim no)
		(in_bom yes)
		(on_board yes)
		(dnp no)
		(fields_autoplaced yes)
		(property "Reference" "U23"
			(at 355.6 212.09 0)
			(effects
				(font
					(size 1.27 1.27)
					(thickness 0.15)
				)
			)
		)
		(property "Value" "TLV73333PDBVT"
			(at 378.46 234.95 0)
			(effects
				(font
					(size 1.27 1.27)
					(thickness 0.15)
				)
				(justify left bottom)
				(hide yes)
			)
		)
		(property "Footprint" "antmicro-footprints:SOT-23-5"
			(at 378.46 237.49 0)
			(effects
				(font
					(size 1.27 1.27)
					(thickness 0.15)
				)
				(justify left bottom)
				(hide yes)
			)
		)
		(property "Datasheet" "https://www.ti.com/lit/ds/symlink/tlv733p.pdf?ts=1702303961350&ref_url=https%253A%252F%252Fwww.ti.com%252Fproduct%252FTLV733P%252Fpart-details%252FTLV73330PDBVR"
			(at 378.46 240.03 0)
			(effects
				(font
					(size 1.27 1.27)
					(thickness 0.15)
				)
				(justify left bottom)
				(hide yes)
			)
		)
		(property "Description" ""
			(at 345.44 219.71 0)
			(effects
				(font
					(size 1.27 1.27)
				)
				(hide yes)
			)
		)
		(property "Manufacturer" "Texas Instruments"
			(at 378.46 224.79 0)
			(effects
				(font
					(size 1.27 1.27)
					(thickness 0.15)
				)
				(justify left bottom)
				(hide yes)
			)
		)
		(property "MPN" "TLV73333PDBVT"
			(at 355.6 214.63 0)
			(effects
				(font
					(size 1.27 1.27)
					(thickness 0.15)
				)
			)
		)
		(property "Author" "Antmicro"
			(at 378.46 229.87 0)
			(effects
				(font
					(size 1.27 1.27)
					(thickness 0.15)
				)
				(justify left bottom)
				(hide yes)
			)
		)
		(property "License" "Apache-2.0"
			(at 378.46 232.41 0)
			(effects
				(font
					(size 1.27 1.27)
					(thickness 0.15)
				)
				(justify left bottom)
				(hide yes)
			)
		)
		(pin "5"
		)
		(pin "3"
		)
		(pin "4"
		)
		(pin "2"
		)
		(pin "1"
		)
		(instances
			(project "com-express-7-baseboard"
				(path ""
					(reference "U23")
					(unit 1)
				)
			)
		)
	)
	(symbol
		(lib_id "antmicroResistorsmisc:R_0R001_0805")
		(at 339.09 134.62 0)
		(unit 1)
		(exclude_from_sim no)
		(in_bom yes)
		(on_board yes)
		(dnp no)
		(property "Reference" "R114"
			(at 341.63 129.54 0)
			(effects
				(font
					(size 1.27 1.27)
					(thickness 0.15)
				)
			)
		)
		(property "Value" "R_0R001_0805"
			(at 359.41 147.32 0)
			(effects
				(font
					(size 1.27 1.27)
					(thickness 0.15)
				)
				(justify left bottom)
				(hide yes)
			)
		)
		(property "Footprint" "antmicro-footprints:R_0805_2012Metric"
			(at 359.41 149.86 0)
			(effects
				(font
					(size 1.27 1.27)
					(thickness 0.15)
				)
				(justify left bottom)
				(hide yes)
			)
		)
		(property "Datasheet" "https://www.eaton.com/content/dam/eaton/products/electronic-components/resources/data-sheet/eaton-msma-automotive-smd-current-sense-resistor-metal-strip-data-sheet-elx1179.pdf"
			(at 359.41 152.4 0)
			(effects
				(font
					(size 1.27 1.27)
					(thickness 0.15)
				)
				(justify left bottom)
				(hide yes)
			)
		)
		(property "Description" ""
			(at 339.09 134.62 0)
			(effects
				(font
					(size 1.27 1.27)
				)
				(hide yes)
			)
		)
		(property "MPN" "MSMA0805R0010FSM"
			(at 359.41 154.94 0)
			(effects
				(font
					(size 1.27 1.27)
					(thickness 0.15)
				)
				(justify left bottom)
				(hide yes)
			)
		)
		(property "Manufacturer" "Eaton"
			(at 359.41 157.48 0)
			(effects
				(font
					(size 1.27 1.27)
					(thickness 0.15)
				)
				(justify left bottom)
				(hide yes)
			)
		)
		(property "License" "Apache-2.0"
			(at 359.41 160.02 0)
			(effects
				(font
					(size 1.27 1.27)
					(thickness 0.15)
				)
				(justify left bottom)
				(hide yes)
			)
		)
		(property "Author" "Antmicro"
			(at 359.41 162.56 0)
			(effects
				(font
					(size 1.27 1.27)
					(thickness 0.15)
				)
				(justify left bottom)
				(hide yes)
			)
		)
		(property "Val" "0R001"
			(at 341.63 132.08 0)
			(effects
				(font
					(size 1.27 1.27)
					(thickness 0.15)
				)
			)
		)
		(property "Tolerance" "1%"
			(at 359.41 144.78 0)
			(effects
				(font
					(size 1.27 1.27)
				)
				(justify left bottom)
				(hide yes)
			)
		)
		(property "Public" "False"
			(at 359.41 165.1 0)
			(effects
				(font
					(size 1.27 1.27)
				)
				(justify left bottom)
				(hide yes)
			)
		)
		(pin "2"
		)
		(pin "1"
		)
		(instances
			(project "com-express-7-baseboard"
				(path ""
					(reference "R114")
					(unit 1)
				)
			)
		)
	)
	(symbol
		(lib_id "antmicroCapacitorspol:C_Pol_68u_16V_Panasonic-TQC-D")
		(at 76.2 224.79 270)
		(unit 1)
		(exclude_from_sim no)
		(in_bom yes)
		(on_board yes)
		(dnp no)
		(property "Reference" "C43"
			(at 78.74 224.79 90)
			(effects
				(font
					(size 1.27 1.27)
					(thickness 0.15)
				)
				(justify left)
			)
		)
		(property "Value" "C_Pol_68u_16V_Panasonic-TQC-D"
			(at 66.04 240.03 0)
			(effects
				(font
					(size 1.27 1.27)
					(thickness 0.15)
				)
				(justify left bottom)
				(hide yes)
			)
		)
		(property "Footprint" "antmicro-footprints:C_Pol_EIA-D"
			(at 63.5 240.03 0)
			(effects
				(font
					(size 1.27 1.27)
					(thickness 0.15)
				)
				(justify left bottom)
				(hide yes)
			)
		)
		(property "Datasheet" "https://industrial.panasonic.com/sa/products/pt/aluminum-cap-smd/models/16TQC68MYF"
			(at 60.96 240.03 0)
			(effects
				(font
					(size 1.27 1.27)
					(thickness 0.15)
				)
				(justify left bottom)
				(hide yes)
			)
		)
		(property "Description" ""
			(at 76.2 224.79 0)
			(effects
				(font
					(size 1.27 1.27)
				)
				(hide yes)
			)
		)
		(property "Author" "Antmicro"
			(at 58.42 240.03 0)
			(effects
				(font
					(size 1.27 1.27)
					(thickness 0.15)
				)
				(justify left bottom)
				(hide yes)
			)
		)
		(property "License" "Apache-2.0"
			(at 55.88 240.03 0)
			(effects
				(font
					(size 1.27 1.27)
					(thickness 0.15)
				)
				(justify left bottom)
				(hide yes)
			)
		)
		(property "MPN" "16TQC68MYF"
			(at 53.34 240.03 0)
			(effects
				(font
					(size 1.27 1.27)
					(thickness 0.15)
				)
				(justify left bottom)
				(hide yes)
			)
		)
		(property "Manufacturer" "Panasonic"
			(at 50.8 240.03 0)
			(effects
				(font
					(size 1.27 1.27)
					(thickness 0.15)
				)
				(justify left bottom)
				(hide yes)
			)
		)
		(property "Val" "68u"
			(at 78.74 227.33 90)
			(effects
				(font
					(size 1.27 1.27)
					(thickness 0.15)
				)
				(justify left)
			)
		)
		(property "Voltage" "16V"
			(at 78.74 229.87 90)
			(effects
				(font
					(size 1.27 1.27)
					(thickness 0.15)
				)
				(justify left)
			)
		)
		(property "Dielectric" "template_dielectric"
			(at 50.8 238.76 0)
			(effects
				(font
					(size 1.27 1.27)
				)
				(justify left bottom)
				(hide yes)
			)
		)
		(property "Public" "False"
			(at 48.26 238.76 0)
			(effects
				(font
					(size 1.27 1.27)
				)
				(justify left bottom)
				(hide yes)
			)
		)
		(pin "1"
		)
		(pin "2"
		)
		(instances
			(project "com-express-7-baseboard"
				(path ""
					(reference "C43")
					(unit 1)
				)
			)
		)
	)
	(symbol
		(lib_id "antmicroResistors0402:R_1k_0402")
		(at 198.12 246.38 90)
		(unit 1)
		(exclude_from_sim no)
		(in_bom yes)
		(on_board yes)
		(dnp no)
		(property "Reference" "R105"
			(at 199.39 242.57 90)
			(effects
				(font
					(size 1.27 1.27)
					(thickness 0.15)
				)
				(justify right)
			)
		)
		(property "Value" "R_1k_0402"
			(at 210.82 226.06 0)
			(effects
				(font
					(size 1.27 1.27)
					(thickness 0.15)
				)
				(justify left bottom)
				(hide yes)
			)
		)
		(property "Footprint" "antmicro-footprints:R_0402_1005Metric"
			(at 213.36 226.06 0)
			(effects
				(font
					(size 1.27 1.27)
					(thickness 0.15)
				)
				(justify left bottom)
				(hide yes)
			)
		)
		(property "Datasheet" "https://www.bourns.com/docs/product-datasheets/cr.pdf"
			(at 215.9 226.06 0)
			(effects
				(font
					(size 1.27 1.27)
					(thickness 0.15)
				)
				(justify left bottom)
				(hide yes)
			)
		)
		(property "Description" ""
			(at 198.12 246.38 0)
			(effects
				(font
					(size 1.27 1.27)
				)
				(hide yes)
			)
		)
		(property "MPN" "CR0402-FX-1001GLF"
			(at 218.44 226.06 0)
			(effects
				(font
					(size 1.27 1.27)
					(thickness 0.15)
				)
				(justify left bottom)
				(hide yes)
			)
		)
		(property "Manufacturer" "Bourns"
			(at 220.98 226.06 0)
			(effects
				(font
					(size 1.27 1.27)
					(thickness 0.15)
				)
				(justify left bottom)
				(hide yes)
			)
		)
		(property "License" "Apache-2.0"
			(at 223.52 226.06 0)
			(effects
				(font
					(size 1.27 1.27)
					(thickness 0.15)
				)
				(justify left bottom)
				(hide yes)
			)
		)
		(property "Author" "Antmicro"
			(at 226.06 226.06 0)
			(effects
				(font
					(size 1.27 1.27)
					(thickness 0.15)
				)
				(justify left bottom)
				(hide yes)
			)
		)
		(property "Val" "1k"
			(at 199.39 245.11 90)
			(effects
				(font
					(size 1.27 1.27)
					(thickness 0.15)
				)
				(justify right)
			)
		)
		(property "Tolerance" "1%"
			(at 208.28 226.06 0)
			(effects
				(font
					(size 1.27 1.27)
				)
				(justify left bottom)
				(hide yes)
			)
		)
		(property "Public" "False"
			(at 228.6 226.06 0)
			(effects
				(font
					(size 1.27 1.27)
				)
				(justify left bottom)
				(hide yes)
			)
		)
		(pin "1"
		)
		(pin "2"
		)
		(instances
			(project "com-express-7-baseboard"
				(path ""
					(reference "R105")
					(unit 1)
				)
			)
		)
	)
	(symbol
		(lib_id "antmicroResistorsmisc:R_0R001_0805")
		(at 58.42 223.52 0)
		(unit 1)
		(exclude_from_sim no)
		(in_bom yes)
		(on_board yes)
		(dnp no)
		(property "Reference" "R85"
			(at 60.96 218.44 0)
			(effects
				(font
					(size 1.27 1.27)
					(thickness 0.15)
				)
			)
		)
		(property "Value" "R_0R001_0805"
			(at 78.74 236.22 0)
			(effects
				(font
					(size 1.27 1.27)
					(thickness 0.15)
				)
				(justify left bottom)
				(hide yes)
			)
		)
		(property "Footprint" "antmicro-footprints:R_0805_2012Metric"
			(at 78.74 238.76 0)
			(effects
				(font
					(size 1.27 1.27)
					(thickness 0.15)
				)
				(justify left bottom)
				(hide yes)
			)
		)
		(property "Datasheet" "https://www.eaton.com/content/dam/eaton/products/electronic-components/resources/data-sheet/eaton-msma-automotive-smd-current-sense-resistor-metal-strip-data-sheet-elx1179.pdf"
			(at 78.74 241.3 0)
			(effects
				(font
					(size 1.27 1.27)
					(thickness 0.15)
				)
				(justify left bottom)
				(hide yes)
			)
		)
		(property "Description" ""
			(at 58.42 223.52 0)
			(effects
				(font
					(size 1.27 1.27)
				)
				(hide yes)
			)
		)
		(property "MPN" "MSMA0805R0010FSM"
			(at 78.74 243.84 0)
			(effects
				(font
					(size 1.27 1.27)
					(thickness 0.15)
				)
				(justify left bottom)
				(hide yes)
			)
		)
		(property "Manufacturer" "Eaton"
			(at 78.74 246.38 0)
			(effects
				(font
					(size 1.27 1.27)
					(thickness 0.15)
				)
				(justify left bottom)
				(hide yes)
			)
		)
		(property "License" "Apache-2.0"
			(at 78.74 248.92 0)
			(effects
				(font
					(size 1.27 1.27)
					(thickness 0.15)
				)
				(justify left bottom)
				(hide yes)
			)
		)
		(property "Author" "Antmicro"
			(at 78.74 251.46 0)
			(effects
				(font
					(size 1.27 1.27)
					(thickness 0.15)
				)
				(justify left bottom)
				(hide yes)
			)
		)
		(property "Val" "0R001"
			(at 60.96 220.98 0)
			(effects
				(font
					(size 1.27 1.27)
					(thickness 0.15)
				)
			)
		)
		(property "Tolerance" "1%"
			(at 78.74 233.68 0)
			(effects
				(font
					(size 1.27 1.27)
				)
				(justify left bottom)
				(hide yes)
			)
		)
		(property "Public" "False"
			(at 78.74 254 0)
			(effects
				(font
					(size 1.27 1.27)
				)
				(justify left bottom)
				(hide yes)
			)
		)
		(pin "2"
		)
		(pin "1"
		)
		(instances
			(project "com-express-7-baseboard"
				(path ""
					(reference "R85")
					(unit 1)
				)
			)
		)
	)
	(symbol
		(lib_id "antmicropower:GND")
		(at 401.32 69.85 0)
		(unit 1)
		(exclude_from_sim no)
		(in_bom yes)
		(on_board yes)
		(dnp no)
		(property "Reference" "#PWR0155"
			(at 410.21 72.39 0)
			(effects
				(font
					(size 1.27 1.27)
					(thickness 0.15)
				)
				(justify left bottom)
				(hide yes)
			)
		)
		(property "Value" "GND"
			(at 401.32 73.66 0)
			(effects
				(font
					(size 1.27 1.27)
					(thickness 0.15)
				)
			)
		)
		(property "Footprint" ""
			(at 410.21 77.47 0)
			(effects
				(font
					(size 1.27 1.27)
					(thickness 0.15)
				)
				(justify left bottom)
				(hide yes)
			)
		)
		(property "Datasheet" ""
			(at 410.21 82.55 0)
			(effects
				(font
					(size 1.27 1.27)
					(thickness 0.15)
				)
				(justify left bottom)
				(hide yes)
			)
		)
		(property "Description" ""
			(at 401.32 69.85 0)
			(effects
				(font
					(size 1.27 1.27)
				)
				(hide yes)
			)
		)
		(property "Author" "Antmicro"
			(at 410.21 77.47 0)
			(effects
				(font
					(size 1.27 1.27)
					(thickness 0.15)
				)
				(justify left bottom)
				(hide yes)
			)
		)
		(property "License" "Apache-2.0"
			(at 410.21 80.01 0)
			(effects
				(font
					(size 1.27 1.27)
					(thickness 0.15)
				)
				(justify left bottom)
				(hide yes)
			)
		)
		(pin "1"
		)
		(instances
			(project "com-express-7-baseboard"
				(path ""
					(reference "#PWR0155")
					(unit 1)
				)
			)
		)
	)
	(symbol
		(lib_id "antmicroLEDIndicationDiscrete:LED_G_0603_LTST-C190GKT")
		(at 236.22 261.62 270)
		(mirror x)
		(unit 1)
		(exclude_from_sim no)
		(in_bom yes)
		(on_board yes)
		(dnp no)
		(property "Reference" "D28"
			(at 236.855 257.175 90)
			(effects
				(font
					(size 1.27 1.27)
				)
				(justify left)
			)
		)
		(property "Value" "LED_G_0603_LTST-C190GKT"
			(at 228.6 238.76 0)
			(effects
				(font
					(size 1.27 1.27)
					(thickness 0.15)
				)
				(justify left bottom)
				(hide yes)
			)
		)
		(property "Footprint" "antmicro-footprints:LED_0603_1608Metric_G"
			(at 226.06 238.76 0)
			(effects
				(font
					(size 1.27 1.27)
					(thickness 0.15)
				)
				(justify left bottom)
				(hide yes)
			)
		)
		(property "Datasheet" "https://media.digikey.com/pdf/Data%20Sheets/Lite-On%20PDFs/LTST-C190GKT.pdf"
			(at 223.52 238.76 0)
			(effects
				(font
					(size 1.27 1.27)
					(thickness 0.15)
				)
				(justify left bottom)
				(hide yes)
			)
		)
		(property "Description" ""
			(at 236.22 261.62 0)
			(effects
				(font
					(size 1.27 1.27)
				)
				(hide yes)
			)
		)
		(property "MPN" "LTST-C190GKT"
			(at 240.03 256.5401 90)
			(effects
				(font
					(size 1.27 1.27)
					(thickness 0.15)
				)
				(justify left)
				(hide yes)
			)
		)
		(property "Manufacturer" "Lite-On"
			(at 218.44 238.76 0)
			(effects
				(font
					(size 1.27 1.27)
					(thickness 0.15)
				)
				(justify left bottom)
				(hide yes)
			)
		)
		(property "Author" "Antmicro"
			(at 215.9 238.76 0)
			(effects
				(font
					(size 1.27 1.27)
					(thickness 0.15)
				)
				(justify left bottom)
				(hide yes)
			)
		)
		(property "License" "Apache-2.0"
			(at 213.36 238.76 0)
			(effects
				(font
					(size 1.27 1.27)
					(thickness 0.15)
				)
				(justify left bottom)
				(hide yes)
			)
		)
		(property "Public" "False"
			(at 218.44 241.3 0)
			(effects
				(font
					(size 1.27 1.27)
				)
				(justify left bottom)
				(hide yes)
			)
		)
		(property "Color" "Green"
			(at 236.855 261.62 90)
			(effects
				(font
					(size 1.27 1.27)
				)
				(justify left)
			)
		)
		(pin "1"
		)
		(pin "2"
		)
		(instances
			(project "com-express-7-baseboard"
				(path ""
					(reference "D28")
					(unit 1)
				)
			)
		)
	)
	(symbol
		(lib_id "antmicropower:GND")
		(at 58.42 132.08 0)
		(mirror y)
		(unit 1)
		(exclude_from_sim no)
		(in_bom yes)
		(on_board yes)
		(dnp no)
		(property "Reference" "#PWR090"
			(at 49.53 134.62 0)
			(effects
				(font
					(size 1.27 1.27)
					(thickness 0.15)
				)
				(justify left bottom)
				(hide yes)
			)
		)
		(property "Value" "GND"
			(at 58.42 135.89 0)
			(effects
				(font
					(size 1.27 1.27)
					(thickness 0.15)
				)
			)
		)
		(property "Footprint" ""
			(at 49.53 139.7 0)
			(effects
				(font
					(size 1.27 1.27)
					(thickness 0.15)
				)
				(justify left bottom)
				(hide yes)
			)
		)
		(property "Datasheet" ""
			(at 49.53 144.78 0)
			(effects
				(font
					(size 1.27 1.27)
					(thickness 0.15)
				)
				(justify left bottom)
				(hide yes)
			)
		)
		(property "Description" ""
			(at 58.42 132.08 0)
			(effects
				(font
					(size 1.27 1.27)
				)
				(hide yes)
			)
		)
		(property "Author" "Antmicro"
			(at 49.53 139.7 0)
			(effects
				(font
					(size 1.27 1.27)
					(thickness 0.15)
				)
				(justify left bottom)
				(hide yes)
			)
		)
		(property "License" "Apache-2.0"
			(at 49.53 142.24 0)
			(effects
				(font
					(size 1.27 1.27)
					(thickness 0.15)
				)
				(justify left bottom)
				(hide yes)
			)
		)
		(pin "1"
		)
		(instances
			(project "com-express-7-baseboard"
				(path ""
					(reference "#PWR090")
					(unit 1)
				)
			)
		)
	)
	(symbol
		(lib_id "antmicroCapacitors0402:C_100n_0402")
		(at 124.46 44.45 0)
		(unit 1)
		(exclude_from_sim no)
		(in_bom yes)
		(on_board yes)
		(dnp no)
		(fields_autoplaced yes)
		(property "Reference" "C47"
			(at 127.0063 38.1 0)
			(effects
				(font
					(size 1.27 1.27)
					(thickness 0.15)
				)
			)
		)
		(property "Value" "C_100n_0402"
			(at 144.78 54.61 0)
			(effects
				(font
					(size 1.27 1.27)
					(thickness 0.15)
				)
				(justify left bottom)
				(hide yes)
			)
		)
		(property "Footprint" "antmicro-footprints:C_0402_1005Metric"
			(at 144.78 57.15 0)
			(effects
				(font
					(size 1.27 1.27)
					(thickness 0.15)
				)
				(justify left bottom)
				(hide yes)
			)
		)
		(property "Datasheet" "https://www.murata.com/products/productdetail?partno=GRM155R61H104KE14%23"
			(at 144.78 59.69 0)
			(effects
				(font
					(size 1.27 1.27)
					(thickness 0.15)
				)
				(justify left bottom)
				(hide yes)
			)
		)
		(property "Description" ""
			(at 124.46 44.45 0)
			(effects
				(font
					(size 1.27 1.27)
				)
				(hide yes)
			)
		)
		(property "MPN" "GRM155R61H104KE14D"
			(at 144.78 62.23 0)
			(effects
				(font
					(size 1.27 1.27)
					(thickness 0.15)
				)
				(justify left bottom)
				(hide yes)
			)
		)
		(property "Manufacturer" "Murata"
			(at 144.78 64.77 0)
			(effects
				(font
					(size 1.27 1.27)
					(thickness 0.15)
				)
				(justify left bottom)
				(hide yes)
			)
		)
		(property "License" "Apache-2.0"
			(at 144.78 67.31 0)
			(effects
				(font
					(size 1.27 1.27)
					(thickness 0.15)
				)
				(justify left bottom)
				(hide yes)
			)
		)
		(property "Author" "Antmicro"
			(at 144.78 69.85 0)
			(effects
				(font
					(size 1.27 1.27)
					(thickness 0.15)
				)
				(justify left bottom)
				(hide yes)
			)
		)
		(property "Val" "100n"
			(at 127.0063 40.64 0)
			(effects
				(font
					(size 1.27 1.27)
					(thickness 0.15)
				)
			)
		)
		(property "Voltage" "50V"
			(at 144.78 72.39 0)
			(effects
				(font
					(size 1.27 1.27)
				)
				(justify left bottom)
				(hide yes)
			)
		)
		(property "Dielectric" "X5R"
			(at 144.78 74.93 0)
			(effects
				(font
					(size 1.27 1.27)
				)
				(justify left bottom)
				(hide yes)
			)
		)
		(property "Public" "False"
			(at 144.78 77.47 0)
			(effects
				(font
					(size 1.27 1.27)
				)
				(justify left bottom)
				(hide yes)
			)
		)
		(pin "2"
		)
		(pin "1"
		)
		(instances
			(project "com-express-7-baseboard"
				(path ""
					(reference "C47")
					(unit 1)
				)
			)
		)
	)
	(symbol
		(lib_id "antmicropower:GND")
		(at 300.99 69.85 0)
		(unit 1)
		(exclude_from_sim no)
		(in_bom yes)
		(on_board yes)
		(dnp no)
		(property "Reference" "#PWR0138"
			(at 309.88 72.39 0)
			(effects
				(font
					(size 1.27 1.27)
					(thickness 0.15)
				)
				(justify left bottom)
				(hide yes)
			)
		)
		(property "Value" "GND"
			(at 300.99 73.66 0)
			(effects
				(font
					(size 1.27 1.27)
					(thickness 0.15)
				)
			)
		)
		(property "Footprint" ""
			(at 309.88 77.47 0)
			(effects
				(font
					(size 1.27 1.27)
					(thickness 0.15)
				)
				(justify left bottom)
				(hide yes)
			)
		)
		(property "Datasheet" ""
			(at 309.88 82.55 0)
			(effects
				(font
					(size 1.27 1.27)
					(thickness 0.15)
				)
				(justify left bottom)
				(hide yes)
			)
		)
		(property "Description" ""
			(at 300.99 69.85 0)
			(effects
				(font
					(size 1.27 1.27)
				)
				(hide yes)
			)
		)
		(property "Author" "Antmicro"
			(at 309.88 77.47 0)
			(effects
				(font
					(size 1.27 1.27)
					(thickness 0.15)
				)
				(justify left bottom)
				(hide yes)
			)
		)
		(property "License" "Apache-2.0"
			(at 309.88 80.01 0)
			(effects
				(font
					(size 1.27 1.27)
					(thickness 0.15)
				)
				(justify left bottom)
				(hide yes)
			)
		)
		(pin "1"
		)
		(instances
			(project "com-express-7-baseboard"
				(path ""
					(reference "#PWR0138")
					(unit 1)
				)
			)
		)
	)
	(symbol
		(lib_id "antmicroTestPoints:TP_0.75mm_SMD")
		(at 257.81 207.01 0)
		(mirror x)
		(unit 1)
		(exclude_from_sim no)
		(in_bom no)
		(on_board yes)
		(dnp no)
		(property "Reference" "TP104"
			(at 261.62 207.01 0)
			(effects
				(font
					(size 1.27 1.27)
					(thickness 0.15)
				)
				(justify left)
			)
		)
		(property "Value" "TP_0.75mm_SMD"
			(at 268.605 203.2 0)
			(effects
				(font
					(size 1.27 1.27)
					(thickness 0.15)
				)
				(justify left bottom)
				(hide yes)
			)
		)
		(property "Footprint" "antmicro-footprints:TP_SMD_0.75mm"
			(at 268.605 200.66 0)
			(effects
				(font
					(size 1.27 1.27)
					(thickness 0.15)
				)
				(justify left bottom)
				(hide yes)
			)
		)
		(property "Datasheet" ""
			(at 275.59 194.31 0)
			(effects
				(font
					(size 1.27 1.27)
					(thickness 0.15)
				)
				(justify left bottom)
				(hide yes)
			)
		)
		(property "Description" ""
			(at 257.81 207.01 0)
			(effects
				(font
					(size 1.27 1.27)
				)
				(hide yes)
			)
		)
		(property "MPN" ""
			(at 268.605 195.58 0)
			(effects
				(font
					(size 1.27 1.27)
					(thickness 0.15)
				)
				(justify left bottom)
				(hide yes)
			)
		)
		(property "Manufacturer" ""
			(at 268.605 200.66 0)
			(effects
				(font
					(size 1.27 1.27)
					(thickness 0.15)
				)
				(justify left bottom)
				(hide yes)
			)
		)
		(property "Author" "Antmicro"
			(at 268.605 198.12 0)
			(effects
				(font
					(size 1.27 1.27)
					(thickness 0.15)
				)
				(justify left bottom)
				(hide yes)
			)
		)
		(property "License" "Apache-2.0"
			(at 268.605 195.58 0)
			(effects
				(font
					(size 1.27 1.27)
					(thickness 0.15)
				)
				(justify left bottom)
				(hide yes)
			)
		)
		(property "Public" "False"
			(at 267.97 193.04 0)
			(effects
				(font
					(size 1.27 1.27)
				)
				(justify left bottom)
				(hide yes)
			)
		)
		(pin "1"
		)
		(instances
			(project "com-express-7-baseboard"
				(path ""
					(reference "TP104")
					(unit 1)
				)
			)
		)
	)
	(symbol
		(lib_id "antmicroCapacitorspol:C_Pol_68u_16V_Panasonic-TQC-D")
		(at 67.31 46.99 270)
		(unit 1)
		(exclude_from_sim no)
		(in_bom yes)
		(on_board yes)
		(dnp no)
		(fields_autoplaced yes)
		(property "Reference" "C41"
			(at 69.85 46.4565 90)
			(effects
				(font
					(size 1.27 1.27)
					(thickness 0.15)
				)
				(justify left)
			)
		)
		(property "Value" "C_Pol_68u_16V_Panasonic-TQC-D"
			(at 57.15 62.23 0)
			(effects
				(font
					(size 1.27 1.27)
					(thickness 0.15)
				)
				(justify left bottom)
				(hide yes)
			)
		)
		(property "Footprint" "antmicro-footprints:C_Pol_EIA-D"
			(at 54.61 62.23 0)
			(effects
				(font
					(size 1.27 1.27)
					(thickness 0.15)
				)
				(justify left bottom)
				(hide yes)
			)
		)
		(property "Datasheet" "https://industrial.panasonic.com/sa/products/pt/aluminum-cap-smd/models/16TQC68MYF"
			(at 52.07 62.23 0)
			(effects
				(font
					(size 1.27 1.27)
					(thickness 0.15)
				)
				(justify left bottom)
				(hide yes)
			)
		)
		(property "Description" ""
			(at 67.31 46.99 0)
			(effects
				(font
					(size 1.27 1.27)
				)
				(hide yes)
			)
		)
		(property "Author" "Antmicro"
			(at 49.53 62.23 0)
			(effects
				(font
					(size 1.27 1.27)
					(thickness 0.15)
				)
				(justify left bottom)
				(hide yes)
			)
		)
		(property "License" "Apache-2.0"
			(at 46.99 62.23 0)
			(effects
				(font
					(size 1.27 1.27)
					(thickness 0.15)
				)
				(justify left bottom)
				(hide yes)
			)
		)
		(property "MPN" "16TQC68MYF"
			(at 44.45 62.23 0)
			(effects
				(font
					(size 1.27 1.27)
					(thickness 0.15)
				)
				(justify left bottom)
				(hide yes)
			)
		)
		(property "Manufacturer" "Panasonic"
			(at 41.91 62.23 0)
			(effects
				(font
					(size 1.27 1.27)
					(thickness 0.15)
				)
				(justify left bottom)
				(hide yes)
			)
		)
		(property "Val" "68u"
			(at 69.85 48.9965 90)
			(effects
				(font
					(size 1.27 1.27)
					(thickness 0.15)
				)
				(justify left)
			)
		)
		(property "Voltage" "16V"
			(at 69.85 51.5365 90)
			(effects
				(font
					(size 1.27 1.27)
					(thickness 0.15)
				)
				(justify left)
			)
		)
		(property "Dielectric" "template_dielectric"
			(at 41.91 60.96 0)
			(effects
				(font
					(size 1.27 1.27)
				)
				(justify left bottom)
				(hide yes)
			)
		)
		(property "Public" "False"
			(at 39.37 60.96 0)
			(effects
				(font
					(size 1.27 1.27)
				)
				(justify left bottom)
				(hide yes)
			)
		)
		(pin "1"
		)
		(pin "2"
		)
		(instances
			(project "com-express-7-baseboard"
				(path ""
					(reference "C41")
					(unit 1)
				)
			)
		)
	)
	(symbol
		(lib_id "antmicropower:+12V_AON")
		(at 67.31 43.18 0)
		(unit 1)
		(exclude_from_sim no)
		(in_bom yes)
		(on_board yes)
		(dnp no)
		(fields_autoplaced yes)
		(property "Reference" "#PWR091"
			(at 67.31 46.99 0)
			(effects
				(font
					(size 1.27 1.27)
				)
				(hide yes)
			)
		)
		(property "Value" "+12V_AON"
			(at 67.31 38.1 0)
			(effects
				(font
					(size 1.27 1.27)
				)
			)
		)
		(property "Footprint" ""
			(at 67.31 43.18 0)
			(effects
				(font
					(size 1.27 1.27)
				)
				(hide yes)
			)
		)
		(property "Datasheet" ""
			(at 67.31 43.18 0)
			(effects
				(font
					(size 1.27 1.27)
				)
				(hide yes)
			)
		)
		(property "Description" ""
			(at 67.31 43.18 0)
			(effects
				(font
					(size 1.27 1.27)
				)
				(hide yes)
			)
		)
		(pin "1"
		)
		(instances
			(project "com-express-7-baseboard"
				(path ""
					(reference "#PWR091")
					(unit 1)
				)
			)
		)
	)
	(symbol
		(lib_id "antmicroResistors0402:R_2k2_0402")
		(at 227.33 222.25 90)
		(unit 1)
		(exclude_from_sim no)
		(in_bom yes)
		(on_board yes)
		(dnp no)
		(property "Reference" "R324"
			(at 228.6 218.44 90)
			(effects
				(font
					(size 1.27 1.27)
					(thickness 0.15)
				)
				(justify right)
			)
		)
		(property "Value" "R_2k2_0402"
			(at 240.03 201.93 0)
			(effects
				(font
					(size 1.27 1.27)
					(thickness 0.15)
				)
				(justify left bottom)
				(hide yes)
			)
		)
		(property "Footprint" "antmicro-footprints:R_0402_1005Metric"
			(at 242.57 201.93 0)
			(effects
				(font
					(size 1.27 1.27)
					(thickness 0.15)
				)
				(justify left bottom)
				(hide yes)
			)
		)
		(property "Datasheet" "https://www.bourns.com/docs/product-datasheets/cr.pdf"
			(at 245.11 201.93 0)
			(effects
				(font
					(size 1.27 1.27)
					(thickness 0.15)
				)
				(justify left bottom)
				(hide yes)
			)
		)
		(property "Description" ""
			(at 227.33 222.25 0)
			(effects
				(font
					(size 1.27 1.27)
				)
				(hide yes)
			)
		)
		(property "MPN" "CR0402-FX-2201GLF"
			(at 247.65 201.93 0)
			(effects
				(font
					(size 1.27 1.27)
					(thickness 0.15)
				)
				(justify left bottom)
				(hide yes)
			)
		)
		(property "Manufacturer" "Bourns"
			(at 250.19 201.93 0)
			(effects
				(font
					(size 1.27 1.27)
					(thickness 0.15)
				)
				(justify left bottom)
				(hide yes)
			)
		)
		(property "License" "Apache-2.0"
			(at 252.73 201.93 0)
			(effects
				(font
					(size 1.27 1.27)
					(thickness 0.15)
				)
				(justify left bottom)
				(hide yes)
			)
		)
		(property "Author" "Antmicro"
			(at 255.27 201.93 0)
			(effects
				(font
					(size 1.27 1.27)
					(thickness 0.15)
				)
				(justify left bottom)
				(hide yes)
			)
		)
		(property "Val" "2k2"
			(at 228.6 220.98 90)
			(effects
				(font
					(size 1.27 1.27)
					(thickness 0.15)
				)
				(justify right)
			)
		)
		(property "Tolerance" "1%"
			(at 237.49 201.93 0)
			(effects
				(font
					(size 1.27 1.27)
				)
				(justify left bottom)
				(hide yes)
			)
		)
		(pin "1"
		)
		(pin "2"
		)
		(instances
			(project "com-express-7-baseboard"
				(path ""
					(reference "R324")
					(unit 1)
				)
			)
		)
	)
	(symbol
		(lib_id "antmicroCapacitorspol:C_Pol_100u_10V_KEMET-T520-B")
		(at 311.15 60.96 270)
		(unit 1)
		(exclude_from_sim no)
		(in_bom yes)
		(on_board yes)
		(dnp no)
		(fields_autoplaced yes)
		(property "Reference" "C64"
			(at 313.69 60.4265 90)
			(effects
				(font
					(size 1.27 1.27)
					(thickness 0.15)
				)
				(justify left)
			)
		)
		(property "Value" "C_Pol_100u_10V_KEMET-T520-B"
			(at 308.61 74.93 0)
			(effects
				(font
					(size 1.27 1.27)
					(thickness 0.15)
				)
				(justify left bottom)
				(hide yes)
			)
		)
		(property "Footprint" "antmicro-footprints:C_Pol_EIA-B"
			(at 303.53 74.93 0)
			(effects
				(font
					(size 1.27 1.27)
					(thickness 0.15)
				)
				(justify left bottom)
				(hide yes)
			)
		)
		(property "Datasheet" "https://www.kemet.com/en/us/capacitors/product/T520B107M010ATE070.html"
			(at 300.99 74.93 0)
			(effects
				(font
					(size 1.27 1.27)
					(thickness 0.15)
				)
				(justify left bottom)
				(hide yes)
			)
		)
		(property "Description" ""
			(at 311.15 60.96 0)
			(effects
				(font
					(size 1.27 1.27)
				)
				(hide yes)
			)
		)
		(property "Val" "100u"
			(at 313.69 62.9665 90)
			(effects
				(font
					(size 1.27 1.27)
					(thickness 0.15)
				)
				(justify left)
			)
		)
		(property "MPN" "T520B107M010ATE070"
			(at 298.45 74.93 0)
			(effects
				(font
					(size 1.27 1.27)
					(thickness 0.15)
				)
				(justify left bottom)
				(hide yes)
			)
		)
		(property "Manufacturer" "KEMET"
			(at 295.91 74.93 0)
			(effects
				(font
					(size 1.27 1.27)
					(thickness 0.15)
				)
				(justify left bottom)
				(hide yes)
			)
		)
		(property "License" "Apache-2.0"
			(at 293.37 74.93 0)
			(effects
				(font
					(size 1.27 1.27)
					(thickness 0.15)
				)
				(justify left bottom)
				(hide yes)
			)
		)
		(property "Author" "Antmicro"
			(at 290.83 74.93 0)
			(effects
				(font
					(size 1.27 1.27)
					(thickness 0.15)
				)
				(justify left bottom)
				(hide yes)
			)
		)
		(property "Voltage" "10V"
			(at 313.69 65.5065 90)
			(effects
				(font
					(size 1.27 1.27)
				)
				(justify left)
			)
		)
		(property "Dielectric" "template_dielectric"
			(at 285.75 74.93 0)
			(effects
				(font
					(size 1.27 1.27)
				)
				(justify left bottom)
				(hide yes)
			)
		)
		(property "Public" "False"
			(at 283.21 74.93 0)
			(effects
				(font
					(size 1.27 1.27)
				)
				(justify left bottom)
				(hide yes)
			)
		)
		(pin "1"
		)
		(pin "2"
		)
		(instances
			(project "com-express-7-baseboard"
				(path ""
					(reference "C64")
					(unit 1)
				)
			)
		)
	)
	(symbol
		(lib_id "antmicroLEDIndicationDiscrete:LED_G_0603_LTST-C190GKT")
		(at 254 214.63 270)
		(mirror x)
		(unit 1)
		(exclude_from_sim no)
		(in_bom yes)
		(on_board yes)
		(dnp no)
		(property "Reference" "D34"
			(at 254.635 210.185 90)
			(effects
				(font
					(size 1.27 1.27)
				)
				(justify left)
			)
		)
		(property "Value" "LED_G_0603_LTST-C190GKT"
			(at 246.38 191.77 0)
			(effects
				(font
					(size 1.27 1.27)
					(thickness 0.15)
				)
				(justify left bottom)
				(hide yes)
			)
		)
		(property "Footprint" "antmicro-footprints:LED_0603_1608Metric_G"
			(at 243.84 191.77 0)
			(effects
				(font
					(size 1.27 1.27)
					(thickness 0.15)
				)
				(justify left bottom)
				(hide yes)
			)
		)
		(property "Datasheet" "https://media.digikey.com/pdf/Data%20Sheets/Lite-On%20PDFs/LTST-C190GKT.pdf"
			(at 241.3 191.77 0)
			(effects
				(font
					(size 1.27 1.27)
					(thickness 0.15)
				)
				(justify left bottom)
				(hide yes)
			)
		)
		(property "Description" ""
			(at 254 214.63 0)
			(effects
				(font
					(size 1.27 1.27)
				)
				(hide yes)
			)
		)
		(property "MPN" "LTST-C190GKT"
			(at 257.81 209.5501 90)
			(effects
				(font
					(size 1.27 1.27)
					(thickness 0.15)
				)
				(justify left)
				(hide yes)
			)
		)
		(property "Manufacturer" "Lite-On"
			(at 236.22 191.77 0)
			(effects
				(font
					(size 1.27 1.27)
					(thickness 0.15)
				)
				(justify left bottom)
				(hide yes)
			)
		)
		(property "Author" "Antmicro"
			(at 233.68 191.77 0)
			(effects
				(font
					(size 1.27 1.27)
					(thickness 0.15)
				)
				(justify left bottom)
				(hide yes)
			)
		)
		(property "License" "Apache-2.0"
			(at 231.14 191.77 0)
			(effects
				(font
					(size 1.27 1.27)
					(thickness 0.15)
				)
				(justify left bottom)
				(hide yes)
			)
		)
		(property "Public" "False"
			(at 236.22 194.31 0)
			(effects
				(font
					(size 1.27 1.27)
				)
				(justify left bottom)
				(hide yes)
			)
		)
		(property "Color" "Green"
			(at 254.635 214.63 90)
			(effects
				(font
					(size 1.27 1.27)
				)
				(justify left)
			)
		)
		(pin "1"
		)
		(pin "2"
		)
		(instances
			(project "com-express-7-baseboard"
				(path ""
					(reference "D34")
					(unit 1)
				)
			)
		)
	)
	(symbol
		(lib_id "antmicropower:+12V_AON")
		(at 227.33 196.85 0)
		(unit 1)
		(exclude_from_sim no)
		(in_bom yes)
		(on_board yes)
		(dnp no)
		(property "Reference" "#PWR0463"
			(at 227.33 200.66 0)
			(effects
				(font
					(size 1.27 1.27)
				)
				(hide yes)
			)
		)
		(property "Value" "+12V_AON"
			(at 227.33 193.04 0)
			(effects
				(font
					(size 1.27 1.27)
				)
			)
		)
		(property "Footprint" ""
			(at 227.33 196.85 0)
			(effects
				(font
					(size 1.27 1.27)
				)
				(hide yes)
			)
		)
		(property "Datasheet" ""
			(at 227.33 196.85 0)
			(effects
				(font
					(size 1.27 1.27)
				)
				(hide yes)
			)
		)
		(property "Description" ""
			(at 227.33 196.85 0)
			(effects
				(font
					(size 1.27 1.27)
				)
				(hide yes)
			)
		)
		(pin "1"
		)
		(instances
			(project "com-express-7-baseboard"
				(path ""
					(reference "#PWR0463")
					(unit 1)
				)
			)
		)
	)
	(symbol
		(lib_id "antmicropower:PWR_FLAG")
		(at 121.92 223.52 270)
		(unit 1)
		(exclude_from_sim no)
		(in_bom yes)
		(on_board yes)
		(dnp no)
		(property "Reference" "#FLG08"
			(at 123.825 223.52 0)
			(effects
				(font
					(size 1.27 1.27)
				)
				(hide yes)
			)
		)
		(property "Value" "PWR_FLAG"
			(at 124.46 223.52 90)
			(effects
				(font
					(size 1.27 1.27)
				)
				(justify left)
			)
		)
		(property "Footprint" ""
			(at 121.92 223.52 0)
			(effects
				(font
					(size 1.27 1.27)
				)
				(hide yes)
			)
		)
		(property "Datasheet" ""
			(at 121.92 223.52 0)
			(effects
				(font
					(size 1.27 1.27)
				)
				(hide yes)
			)
		)
		(property "Description" ""
			(at 121.92 223.52 0)
			(effects
				(font
					(size 1.27 1.27)
				)
				(hide yes)
			)
		)
		(pin "1"
		)
		(instances
			(project "com-express-7-baseboard"
				(path ""
					(reference "#FLG08")
					(unit 1)
				)
			)
		)
	)
	(symbol
		(lib_id "antmicropower:GND")
		(at 276.86 209.55 0)
		(unit 1)
		(exclude_from_sim no)
		(in_bom yes)
		(on_board yes)
		(dnp no)
		(property "Reference" "#PWR0467"
			(at 285.75 212.09 0)
			(effects
				(font
					(size 1.27 1.27)
					(thickness 0.15)
				)
				(justify left bottom)
				(hide yes)
			)
		)
		(property "Value" "GND"
			(at 276.86 213.36 0)
			(effects
				(font
					(size 1.27 1.27)
					(thickness 0.15)
				)
			)
		)
		(property "Footprint" ""
			(at 285.75 217.17 0)
			(effects
				(font
					(size 1.27 1.27)
					(thickness 0.15)
				)
				(justify left bottom)
				(hide yes)
			)
		)
		(property "Datasheet" ""
			(at 285.75 222.25 0)
			(effects
				(font
					(size 1.27 1.27)
					(thickness 0.15)
				)
				(justify left bottom)
				(hide yes)
			)
		)
		(property "Description" ""
			(at 276.86 209.55 0)
			(effects
				(font
					(size 1.27 1.27)
				)
				(hide yes)
			)
		)
		(property "Author" "Antmicro"
			(at 285.75 217.17 0)
			(effects
				(font
					(size 1.27 1.27)
					(thickness 0.15)
				)
				(justify left bottom)
				(hide yes)
			)
		)
		(property "License" "Apache-2.0"
			(at 285.75 219.71 0)
			(effects
				(font
					(size 1.27 1.27)
					(thickness 0.15)
				)
				(justify left bottom)
				(hide yes)
			)
		)
		(pin "1"
		)
		(instances
			(project "com-express-7-baseboard"
				(path ""
					(reference "#PWR0467")
					(unit 1)
				)
			)
		)
	)
	(symbol
		(lib_id "antmicroResistors0402:R_0R_0402")
		(at 265.43 149.86 0)
		(unit 1)
		(exclude_from_sim no)
		(in_bom yes)
		(on_board yes)
		(dnp no)
		(property "Reference" "R106"
			(at 262.89 148.59 0)
			(effects
				(font
					(size 1.27 1.27)
					(thickness 0.15)
				)
			)
		)
		(property "Value" "R_0R_0402"
			(at 285.75 162.56 0)
			(effects
				(font
					(size 1.27 1.27)
					(thickness 0.15)
				)
				(justify left bottom)
				(hide yes)
			)
		)
		(property "Footprint" "antmicro-footprints:R_0402_1005Metric"
			(at 285.75 165.1 0)
			(effects
				(font
					(size 1.27 1.27)
					(thickness 0.15)
				)
				(justify left bottom)
				(hide yes)
			)
		)
		(property "Datasheet" "https://industrial.panasonic.com/cdbs/www-data/pdf/RDA0000/AOA0000C301.pdf"
			(at 285.75 167.64 0)
			(effects
				(font
					(size 1.27 1.27)
					(thickness 0.15)
				)
				(justify left bottom)
				(hide yes)
			)
		)
		(property "Description" ""
			(at 265.43 149.86 0)
			(effects
				(font
					(size 1.27 1.27)
				)
				(hide yes)
			)
		)
		(property "MPN" "ERJ2GE0R00X"
			(at 285.75 170.18 0)
			(effects
				(font
					(size 1.27 1.27)
					(thickness 0.15)
				)
				(justify left bottom)
				(hide yes)
			)
		)
		(property "Manufacturer" "Panasonic"
			(at 285.75 172.72 0)
			(effects
				(font
					(size 1.27 1.27)
					(thickness 0.15)
				)
				(justify left bottom)
				(hide yes)
			)
		)
		(property "License" "Apache-2.0"
			(at 285.75 175.26 0)
			(effects
				(font
					(size 1.27 1.27)
					(thickness 0.15)
				)
				(justify left bottom)
				(hide yes)
			)
		)
		(property "Author" "Antmicro"
			(at 285.75 177.8 0)
			(effects
				(font
					(size 1.27 1.27)
					(thickness 0.15)
				)
				(justify left bottom)
				(hide yes)
			)
		)
		(property "Val" "0R"
			(at 271.78 148.59 0)
			(effects
				(font
					(size 1.27 1.27)
					(thickness 0.15)
				)
			)
		)
		(property "Tolerance" "~"
			(at 285.75 160.02 0)
			(effects
				(font
					(size 1.27 1.27)
				)
				(justify left bottom)
				(hide yes)
			)
		)
		(property "Current" "1A"
			(at 285.75 180.34 0)
			(effects
				(font
					(size 1.27 1.27)
					(thickness 0.15)
				)
				(justify left bottom)
				(hide yes)
			)
		)
		(property "Public" "False"
			(at 285.75 180.34 0)
			(effects
				(font
					(size 1.27 1.27)
				)
				(justify left bottom)
				(hide yes)
			)
		)
		(pin "1"
		)
		(pin "2"
		)
		(instances
			(project "com-express-7-baseboard"
				(path ""
					(reference "R106")
					(unit 1)
				)
			)
		)
	)
	(symbol
		(lib_id "antmicropower:GND")
		(at 149.86 63.5 0)
		(unit 1)
		(exclude_from_sim no)
		(in_bom yes)
		(on_board yes)
		(dnp no)
		(property "Reference" "#PWR0112"
			(at 158.75 66.04 0)
			(effects
				(font
					(size 1.27 1.27)
					(thickness 0.15)
				)
				(justify left bottom)
				(hide yes)
			)
		)
		(property "Value" "GND"
			(at 149.86 67.31 0)
			(effects
				(font
					(size 1.27 1.27)
					(thickness 0.15)
				)
			)
		)
		(property "Footprint" ""
			(at 158.75 71.12 0)
			(effects
				(font
					(size 1.27 1.27)
					(thickness 0.15)
				)
				(justify left bottom)
				(hide yes)
			)
		)
		(property "Datasheet" ""
			(at 158.75 76.2 0)
			(effects
				(font
					(size 1.27 1.27)
					(thickness 0.15)
				)
				(justify left bottom)
				(hide yes)
			)
		)
		(property "Description" ""
			(at 149.86 63.5 0)
			(effects
				(font
					(size 1.27 1.27)
				)
				(hide yes)
			)
		)
		(property "Author" "Antmicro"
			(at 158.75 71.12 0)
			(effects
				(font
					(size 1.27 1.27)
					(thickness 0.15)
				)
				(justify left bottom)
				(hide yes)
			)
		)
		(property "License" "Apache-2.0"
			(at 158.75 73.66 0)
			(effects
				(font
					(size 1.27 1.27)
					(thickness 0.15)
				)
				(justify left bottom)
				(hide yes)
			)
		)
		(pin "1"
		)
		(instances
			(project "com-express-7-baseboard"
				(path ""
					(reference "#PWR0112")
					(unit 1)
				)
			)
		)
	)
	(symbol
		(lib_id "antmicroTestPoints:TP_0.75mm_SMD")
		(at 257.81 201.93 0)
		(mirror x)
		(unit 1)
		(exclude_from_sim no)
		(in_bom no)
		(on_board yes)
		(dnp no)
		(property "Reference" "TP102"
			(at 261.62 201.93 0)
			(effects
				(font
					(size 1.27 1.27)
					(thickness 0.15)
				)
				(justify left)
			)
		)
		(property "Value" "TP_0.75mm_SMD"
			(at 268.605 198.12 0)
			(effects
				(font
					(size 1.27 1.27)
					(thickness 0.15)
				)
				(justify left bottom)
				(hide yes)
			)
		)
		(property "Footprint" "antmicro-footprints:TP_SMD_0.75mm"
			(at 268.605 195.58 0)
			(effects
				(font
					(size 1.27 1.27)
					(thickness 0.15)
				)
				(justify left bottom)
				(hide yes)
			)
		)
		(property "Datasheet" ""
			(at 275.59 189.23 0)
			(effects
				(font
					(size 1.27 1.27)
					(thickness 0.15)
				)
				(justify left bottom)
				(hide yes)
			)
		)
		(property "Description" ""
			(at 257.81 201.93 0)
			(effects
				(font
					(size 1.27 1.27)
				)
				(hide yes)
			)
		)
		(property "MPN" ""
			(at 268.605 190.5 0)
			(effects
				(font
					(size 1.27 1.27)
					(thickness 0.15)
				)
				(justify left bottom)
				(hide yes)
			)
		)
		(property "Manufacturer" ""
			(at 268.605 195.58 0)
			(effects
				(font
					(size 1.27 1.27)
					(thickness 0.15)
				)
				(justify left bottom)
				(hide yes)
			)
		)
		(property "Author" "Antmicro"
			(at 268.605 193.04 0)
			(effects
				(font
					(size 1.27 1.27)
					(thickness 0.15)
				)
				(justify left bottom)
				(hide yes)
			)
		)
		(property "License" "Apache-2.0"
			(at 268.605 190.5 0)
			(effects
				(font
					(size 1.27 1.27)
					(thickness 0.15)
				)
				(justify left bottom)
				(hide yes)
			)
		)
		(property "Public" "False"
			(at 267.97 187.96 0)
			(effects
				(font
					(size 1.27 1.27)
				)
				(justify left bottom)
				(hide yes)
			)
		)
		(pin "1"
		)
		(instances
			(project "com-express-7-baseboard"
				(path ""
					(reference "TP102")
					(unit 1)
				)
			)
		)
	)
	(symbol
		(lib_id "antmicroTestPoints:TP_0.75mm_SMD")
		(at 279.4 207.01 0)
		(mirror x)
		(unit 1)
		(exclude_from_sim no)
		(in_bom no)
		(on_board yes)
		(dnp no)
		(property "Reference" "TP105"
			(at 283.21 207.01 0)
			(effects
				(font
					(size 1.27 1.27)
					(thickness 0.15)
				)
				(justify left)
			)
		)
		(property "Value" "TP_0.75mm_SMD"
			(at 290.195 203.2 0)
			(effects
				(font
					(size 1.27 1.27)
					(thickness 0.15)
				)
				(justify left bottom)
				(hide yes)
			)
		)
		(property "Footprint" "antmicro-footprints:TP_SMD_0.75mm"
			(at 290.195 200.66 0)
			(effects
				(font
					(size 1.27 1.27)
					(thickness 0.15)
				)
				(justify left bottom)
				(hide yes)
			)
		)
		(property "Datasheet" ""
			(at 297.18 194.31 0)
			(effects
				(font
					(size 1.27 1.27)
					(thickness 0.15)
				)
				(justify left bottom)
				(hide yes)
			)
		)
		(property "Description" ""
			(at 279.4 207.01 0)
			(effects
				(font
					(size 1.27 1.27)
				)
				(hide yes)
			)
		)
		(property "MPN" ""
			(at 290.195 195.58 0)
			(effects
				(font
					(size 1.27 1.27)
					(thickness 0.15)
				)
				(justify left bottom)
				(hide yes)
			)
		)
		(property "Manufacturer" ""
			(at 290.195 200.66 0)
			(effects
				(font
					(size 1.27 1.27)
					(thickness 0.15)
				)
				(justify left bottom)
				(hide yes)
			)
		)
		(property "Author" "Antmicro"
			(at 290.195 198.12 0)
			(effects
				(font
					(size 1.27 1.27)
					(thickness 0.15)
				)
				(justify left bottom)
				(hide yes)
			)
		)
		(property "License" "Apache-2.0"
			(at 290.195 195.58 0)
			(effects
				(font
					(size 1.27 1.27)
					(thickness 0.15)
				)
				(justify left bottom)
				(hide yes)
			)
		)
		(property "Public" "False"
			(at 289.56 193.04 0)
			(effects
				(font
					(size 1.27 1.27)
				)
				(justify left bottom)
				(hide yes)
			)
		)
		(pin "1"
		)
		(instances
			(project "com-express-7-baseboard"
				(path ""
					(reference "TP105")
					(unit 1)
				)
			)
		)
	)
	(symbol
		(lib_id "antmicroResistors0402:R_30k_0402")
		(at 309.88 140.97 90)
		(unit 1)
		(exclude_from_sim no)
		(in_bom yes)
		(on_board yes)
		(dnp no)
		(fields_autoplaced yes)
		(property "Reference" "R111"
			(at 312.42 137.1599 90)
			(effects
				(font
					(size 1.27 1.27)
					(thickness 0.15)
				)
				(justify right)
			)
		)
		(property "Value" "R_30k_0402"
			(at 322.58 120.65 0)
			(effects
				(font
					(size 1.27 1.27)
					(thickness 0.15)
				)
				(justify left bottom)
				(hide yes)
			)
		)
		(property "Footprint" "antmicro-footprints:R_0402_1005Metric"
			(at 325.12 120.65 0)
			(effects
				(font
					(size 1.27 1.27)
					(thickness 0.15)
				)
				(justify left bottom)
				(hide yes)
			)
		)
		(property "Datasheet" "https://www.bourns.com/docs/product-datasheets/cr.pdf"
			(at 327.66 120.65 0)
			(effects
				(font
					(size 1.27 1.27)
					(thickness 0.15)
				)
				(justify left bottom)
				(hide yes)
			)
		)
		(property "Description" ""
			(at 309.88 140.97 0)
			(effects
				(font
					(size 1.27 1.27)
				)
				(hide yes)
			)
		)
		(property "MPN" "CR0402-FX-3002GLF"
			(at 330.2 120.65 0)
			(effects
				(font
					(size 1.27 1.27)
					(thickness 0.15)
				)
				(justify left bottom)
				(hide yes)
			)
		)
		(property "Manufacturer" "Bourns"
			(at 332.74 120.65 0)
			(effects
				(font
					(size 1.27 1.27)
					(thickness 0.15)
				)
				(justify left bottom)
				(hide yes)
			)
		)
		(property "License" "Apache-2.0"
			(at 335.28 120.65 0)
			(effects
				(font
					(size 1.27 1.27)
					(thickness 0.15)
				)
				(justify left bottom)
				(hide yes)
			)
		)
		(property "Author" "Antmicro"
			(at 337.82 120.65 0)
			(effects
				(font
					(size 1.27 1.27)
					(thickness 0.15)
				)
				(justify left bottom)
				(hide yes)
			)
		)
		(property "Val" "30k"
			(at 312.42 139.6999 90)
			(effects
				(font
					(size 1.27 1.27)
					(thickness 0.15)
				)
				(justify right)
			)
		)
		(property "Tolerance" "1%"
			(at 320.04 120.65 0)
			(effects
				(font
					(size 1.27 1.27)
				)
				(justify left bottom)
				(hide yes)
			)
		)
		(property "Public" "False"
			(at 340.36 120.65 0)
			(effects
				(font
					(size 1.27 1.27)
				)
				(justify left bottom)
				(hide yes)
			)
		)
		(pin "1"
		)
		(pin "2"
		)
		(instances
			(project "com-express-7-baseboard"
				(path ""
					(reference "R111")
					(unit 1)
				)
			)
		)
	)
	(symbol
		(lib_id "antmicropower:+5V")
		(at 401.32 53.34 0)
		(unit 1)
		(exclude_from_sim no)
		(in_bom yes)
		(on_board yes)
		(dnp no)
		(property "Reference" "#PWR0154"
			(at 416.56 55.88 0)
			(effects
				(font
					(size 1.27 1.27)
					(thickness 0.15)
				)
				(justify left bottom)
				(hide yes)
			)
		)
		(property "Value" "+5V"
			(at 401.32 49.53 0)
			(effects
				(font
					(size 1.27 1.27)
					(thickness 0.15)
				)
			)
		)
		(property "Footprint" ""
			(at 416.56 60.96 0)
			(effects
				(font
					(size 1.27 1.27)
					(thickness 0.15)
				)
				(justify left bottom)
				(hide yes)
			)
		)
		(property "Datasheet" ""
			(at 416.56 63.5 0)
			(effects
				(font
					(size 1.27 1.27)
					(thickness 0.15)
				)
				(justify left bottom)
				(hide yes)
			)
		)
		(property "Description" ""
			(at 401.32 53.34 0)
			(effects
				(font
					(size 1.27 1.27)
				)
				(hide yes)
			)
		)
		(property "Author" "Antmicro"
			(at 416.56 60.96 0)
			(effects
				(font
					(size 1.27 1.27)
					(thickness 0.15)
				)
				(justify left bottom)
				(hide yes)
			)
		)
		(property "License" "Apache-2.0"
			(at 416.56 63.5 0)
			(effects
				(font
					(size 1.27 1.27)
					(thickness 0.15)
				)
				(justify left bottom)
				(hide yes)
			)
		)
		(pin "1"
		)
		(instances
			(project "com-express-7-baseboard"
				(path ""
					(reference "#PWR0154")
					(unit 1)
				)
			)
		)
	)
	(symbol
		(lib_id "antmicropower:+3V3")
		(at 199.39 128.27 0)
		(unit 1)
		(exclude_from_sim no)
		(in_bom yes)
		(on_board yes)
		(dnp no)
		(property "Reference" "#PWR0123"
			(at 214.63 128.27 0)
			(effects
				(font
					(size 1.27 1.27)
					(thickness 0.15)
				)
				(justify left bottom)
				(hide yes)
			)
		)
		(property "Value" "+3V3"
			(at 199.39 123.19 0)
			(effects
				(font
					(size 1.27 1.27)
					(thickness 0.15)
				)
			)
		)
		(property "Footprint" ""
			(at 214.63 135.89 0)
			(effects
				(font
					(size 1.27 1.27)
					(thickness 0.15)
				)
				(justify left bottom)
				(hide yes)
			)
		)
		(property "Datasheet" ""
			(at 214.63 138.43 0)
			(effects
				(font
					(size 1.27 1.27)
					(thickness 0.15)
				)
				(justify left bottom)
				(hide yes)
			)
		)
		(property "Description" ""
			(at 199.39 128.27 0)
			(effects
				(font
					(size 1.27 1.27)
				)
				(hide yes)
			)
		)
		(property "Author" "Antmicro"
			(at 214.63 130.81 0)
			(effects
				(font
					(size 1.27 1.27)
					(thickness 0.15)
				)
				(justify left bottom)
				(hide yes)
			)
		)
		(property "License" "Apache-2.0"
			(at 214.63 133.35 0)
			(effects
				(font
					(size 1.27 1.27)
					(thickness 0.15)
				)
				(justify left bottom)
				(hide yes)
			)
		)
		(pin "1"
		)
		(instances
			(project "com-express-7-baseboard"
				(path ""
					(reference "#PWR0123")
					(unit 1)
				)
			)
		)
	)
	(symbol
		(lib_id "antmicroResistors0402:R_2k2_0402")
		(at 271.78 251.46 90)
		(unit 1)
		(exclude_from_sim no)
		(in_bom yes)
		(on_board yes)
		(dnp no)
		(property "Reference" "R319"
			(at 273.05 247.65 90)
			(effects
				(font
					(size 1.27 1.27)
					(thickness 0.15)
				)
				(justify right)
			)
		)
		(property "Value" "R_2k2_0402"
			(at 284.48 231.14 0)
			(effects
				(font
					(size 1.27 1.27)
					(thickness 0.15)
				)
				(justify left bottom)
				(hide yes)
			)
		)
		(property "Footprint" "antmicro-footprints:R_0402_1005Metric"
			(at 287.02 231.14 0)
			(effects
				(font
					(size 1.27 1.27)
					(thickness 0.15)
				)
				(justify left bottom)
				(hide yes)
			)
		)
		(property "Datasheet" "https://www.bourns.com/docs/product-datasheets/cr.pdf"
			(at 289.56 231.14 0)
			(effects
				(font
					(size 1.27 1.27)
					(thickness 0.15)
				)
				(justify left bottom)
				(hide yes)
			)
		)
		(property "Description" ""
			(at 271.78 251.46 0)
			(effects
				(font
					(size 1.27 1.27)
				)
				(hide yes)
			)
		)
		(property "MPN" "CR0402-FX-2201GLF"
			(at 292.1 231.14 0)
			(effects
				(font
					(size 1.27 1.27)
					(thickness 0.15)
				)
				(justify left bottom)
				(hide yes)
			)
		)
		(property "Manufacturer" "Bourns"
			(at 294.64 231.14 0)
			(effects
				(font
					(size 1.27 1.27)
					(thickness 0.15)
				)
				(justify left bottom)
				(hide yes)
			)
		)
		(property "License" "Apache-2.0"
			(at 297.18 231.14 0)
			(effects
				(font
					(size 1.27 1.27)
					(thickness 0.15)
				)
				(justify left bottom)
				(hide yes)
			)
		)
		(property "Author" "Antmicro"
			(at 299.72 231.14 0)
			(effects
				(font
					(size 1.27 1.27)
					(thickness 0.15)
				)
				(justify left bottom)
				(hide yes)
			)
		)
		(property "Val" "2k2"
			(at 273.05 250.19 90)
			(effects
				(font
					(size 1.27 1.27)
					(thickness 0.15)
				)
				(justify right)
			)
		)
		(property "Tolerance" "1%"
			(at 281.94 231.14 0)
			(effects
				(font
					(size 1.27 1.27)
				)
				(justify left bottom)
				(hide yes)
			)
		)
		(pin "1"
		)
		(pin "2"
		)
		(instances
			(project "com-express-7-baseboard"
				(path ""
					(reference "R319")
					(unit 1)
				)
			)
		)
	)
	(symbol
		(lib_id "antmicropower:PWR_FLAG")
		(at 179.07 49.53 270)
		(unit 1)
		(exclude_from_sim no)
		(in_bom yes)
		(on_board yes)
		(dnp no)
		(fields_autoplaced yes)
		(property "Reference" "#FLG09"
			(at 180.975 49.53 0)
			(effects
				(font
					(size 1.27 1.27)
				)
				(hide yes)
			)
		)
		(property "Value" "PWR_FLAG"
			(at 182.88 49.5299 90)
			(effects
				(font
					(size 1.27 1.27)
				)
				(justify left)
			)
		)
		(property "Footprint" ""
			(at 179.07 49.53 0)
			(effects
				(font
					(size 1.27 1.27)
				)
				(hide yes)
			)
		)
		(property "Datasheet" ""
			(at 179.07 49.53 0)
			(effects
				(font
					(size 1.27 1.27)
				)
				(hide yes)
			)
		)
		(property "Description" ""
			(at 179.07 49.53 0)
			(effects
				(font
					(size 1.27 1.27)
				)
				(hide yes)
			)
		)
		(pin "1"
		)
		(instances
			(project "com-express-7-baseboard"
				(path ""
					(reference "#FLG09")
					(unit 1)
				)
			)
		)
	)
	(symbol
		(lib_id "antmicroCapacitors0402:C_1u_0402")
		(at 375.92 226.06 270)
		(mirror x)
		(unit 1)
		(exclude_from_sim no)
		(in_bom yes)
		(on_board yes)
		(dnp no)
		(fields_autoplaced yes)
		(property "Reference" "C69"
			(at 373.38 222.2435 90)
			(effects
				(font
					(size 1.27 1.27)
					(thickness 0.15)
				)
				(justify right)
			)
		)
		(property "Value" "C_1u_0402"
			(at 365.76 205.74 0)
			(effects
				(font
					(size 1.27 1.27)
					(thickness 0.15)
				)
				(justify left bottom)
				(hide yes)
			)
		)
		(property "Footprint" "antmicro-footprints:C_0402_1005Metric"
			(at 363.22 205.74 0)
			(effects
				(font
					(size 1.27 1.27)
					(thickness 0.15)
				)
				(justify left bottom)
				(hide yes)
			)
		)
		(property "Datasheet" "https://product.tdk.com/en/search/capacitor/ceramic/mlcc/info?part_no=C1005X6S1A105K050BC"
			(at 360.68 205.74 0)
			(effects
				(font
					(size 1.27 1.27)
					(thickness 0.15)
				)
				(justify left bottom)
				(hide yes)
			)
		)
		(property "Description" ""
			(at 375.92 226.06 0)
			(effects
				(font
					(size 1.27 1.27)
				)
				(hide yes)
			)
		)
		(property "MPN" "C1005X6S1A105K050BC"
			(at 358.14 205.74 0)
			(effects
				(font
					(size 1.27 1.27)
					(thickness 0.15)
				)
				(justify left bottom)
				(hide yes)
			)
		)
		(property "Manufacturer" "TDK"
			(at 355.6 205.74 0)
			(effects
				(font
					(size 1.27 1.27)
					(thickness 0.15)
				)
				(justify left bottom)
				(hide yes)
			)
		)
		(property "License" "Apache-2.0"
			(at 353.06 205.74 0)
			(effects
				(font
					(size 1.27 1.27)
					(thickness 0.15)
				)
				(justify left bottom)
				(hide yes)
			)
		)
		(property "Author" "Antmicro"
			(at 350.52 205.74 0)
			(effects
				(font
					(size 1.27 1.27)
					(thickness 0.15)
				)
				(justify left bottom)
				(hide yes)
			)
		)
		(property "Val" "1u"
			(at 373.38 224.7835 90)
			(effects
				(font
					(size 1.27 1.27)
					(thickness 0.15)
				)
				(justify right)
			)
		)
		(property "Voltage" ""
			(at 347.98 205.74 0)
			(effects
				(font
					(size 1.27 1.27)
				)
				(justify left bottom)
				(hide yes)
			)
		)
		(property "Dielectric" ""
			(at 345.44 205.74 0)
			(effects
				(font
					(size 1.27 1.27)
				)
				(justify left bottom)
				(hide yes)
			)
		)
		(property "Public" "False"
			(at 342.9 205.74 0)
			(effects
				(font
					(size 1.27 1.27)
				)
				(justify left bottom)
				(hide yes)
			)
		)
		(pin "1"
		)
		(pin "2"
		)
		(instances
			(project "com-express-7-baseboard"
				(path ""
					(reference "C69")
					(unit 1)
				)
			)
		)
	)
	(symbol
		(lib_id "antmicroTransistorsBipolarSingle:MMBT3904LT1G")
		(at 265.43 265.43 0)
		(unit 1)
		(exclude_from_sim no)
		(in_bom yes)
		(on_board yes)
		(dnp no)
		(fields_autoplaced yes)
		(property "Reference" "Q14"
			(at 274.32 264.16 0)
			(effects
				(font
					(size 1.27 1.27)
					(thickness 0.15)
				)
				(justify left)
			)
		)
		(property "Value" "MMBT3904LT1G"
			(at 280.67 275.59 0)
			(effects
				(font
					(size 1.27 1.27)
					(thickness 0.15)
				)
				(justify left bottom)
				(hide yes)
			)
		)
		(property "Footprint" "antmicro-footprints:SOT-23-3"
			(at 280.67 278.13 0)
			(effects
				(font
					(size 1.27 1.27)
					(thickness 0.15)
				)
				(justify left bottom)
				(hide yes)
			)
		)
		(property "Datasheet" "https://eu.mouser.com/datasheet/2/308/1/MMBT3904LT1_D-2316262.pdf"
			(at 280.67 280.67 0)
			(effects
				(font
					(size 1.27 1.27)
					(thickness 0.15)
				)
				(justify left bottom)
				(hide yes)
			)
		)
		(property "Description" ""
			(at 265.43 265.43 0)
			(effects
				(font
					(size 1.27 1.27)
				)
				(hide yes)
			)
		)
		(property "MPN" "MMBT3904LT1G"
			(at 274.32 266.7 0)
			(effects
				(font
					(size 1.27 1.27)
					(thickness 0.15)
				)
				(justify left)
			)
		)
		(property "Manufacturer" "Onsemi"
			(at 280.67 283.21 0)
			(effects
				(font
					(size 1.27 1.27)
					(thickness 0.15)
				)
				(justify left bottom)
				(hide yes)
			)
		)
		(property "Author" "Antmicro"
			(at 280.67 285.75 0)
			(effects
				(font
					(size 1.27 1.27)
					(thickness 0.15)
				)
				(justify left bottom)
				(hide yes)
			)
		)
		(property "License" "Apache-2.0"
			(at 280.67 288.29 0)
			(effects
				(font
					(size 1.27 1.27)
					(thickness 0.15)
				)
				(justify left bottom)
				(hide yes)
			)
		)
		(property "Public" "False"
			(at 288.29 285.75 0)
			(effects
				(font
					(size 1.27 1.27)
				)
				(justify left bottom)
				(hide yes)
			)
		)
		(pin "2"
		)
		(pin "1"
		)
		(pin "3"
		)
		(instances
			(project "com-express-7-baseboard"
				(path ""
					(reference "Q14")
					(unit 1)
				)
			)
		)
	)
	(symbol
		(lib_id "antmicroCapacitors0402:C_1u_0402")
		(at 351.79 144.78 90)
		(unit 1)
		(exclude_from_sim no)
		(in_bom yes)
		(on_board yes)
		(dnp no)
		(fields_autoplaced yes)
		(property "Reference" "C68"
			(at 354.33 140.9635 90)
			(effects
				(font
					(size 1.27 1.27)
					(thickness 0.15)
				)
				(justify right)
			)
		)
		(property "Value" "C_1u_0402"
			(at 361.95 124.46 0)
			(effects
				(font
					(size 1.27 1.27)
					(thickness 0.15)
				)
				(justify left bottom)
				(hide yes)
			)
		)
		(property "Footprint" "antmicro-footprints:C_0402_1005Metric"
			(at 364.49 124.46 0)
			(effects
				(font
					(size 1.27 1.27)
					(thickness 0.15)
				)
				(justify left bottom)
				(hide yes)
			)
		)
		(property "Datasheet" "https://product.tdk.com/en/search/capacitor/ceramic/mlcc/info?part_no=C1005X6S1A105K050BC"
			(at 367.03 124.46 0)
			(effects
				(font
					(size 1.27 1.27)
					(thickness 0.15)
				)
				(justify left bottom)
				(hide yes)
			)
		)
		(property "Description" ""
			(at 351.79 144.78 0)
			(effects
				(font
					(size 1.27 1.27)
				)
				(hide yes)
			)
		)
		(property "MPN" "C1005X6S1A105K050BC"
			(at 369.57 124.46 0)
			(effects
				(font
					(size 1.27 1.27)
					(thickness 0.15)
				)
				(justify left bottom)
				(hide yes)
			)
		)
		(property "Manufacturer" "TDK"
			(at 372.11 124.46 0)
			(effects
				(font
					(size 1.27 1.27)
					(thickness 0.15)
				)
				(justify left bottom)
				(hide yes)
			)
		)
		(property "License" "Apache-2.0"
			(at 374.65 124.46 0)
			(effects
				(font
					(size 1.27 1.27)
					(thickness 0.15)
				)
				(justify left bottom)
				(hide yes)
			)
		)
		(property "Author" "Antmicro"
			(at 377.19 124.46 0)
			(effects
				(font
					(size 1.27 1.27)
					(thickness 0.15)
				)
				(justify left bottom)
				(hide yes)
			)
		)
		(property "Val" "1u"
			(at 354.33 143.5035 90)
			(effects
				(font
					(size 1.27 1.27)
					(thickness 0.15)
				)
				(justify right)
			)
		)
		(property "Voltage" ""
			(at 379.73 124.46 0)
			(effects
				(font
					(size 1.27 1.27)
				)
				(justify left bottom)
				(hide yes)
			)
		)
		(property "Dielectric" ""
			(at 382.27 124.46 0)
			(effects
				(font
					(size 1.27 1.27)
				)
				(justify left bottom)
				(hide yes)
			)
		)
		(property "Public" "False"
			(at 384.81 124.46 0)
			(effects
				(font
					(size 1.27 1.27)
				)
				(justify left bottom)
				(hide yes)
			)
		)
		(pin "1"
		)
		(pin "2"
		)
		(instances
			(project "com-express-7-baseboard"
				(path ""
					(reference "C68")
					(unit 1)
				)
			)
		)
	)
	(symbol
		(lib_id "antmicroCapacitors0402:C_100n_0402")
		(at 161.29 254 90)
		(unit 1)
		(exclude_from_sim no)
		(in_bom yes)
		(on_board yes)
		(dnp no)
		(fields_autoplaced yes)
		(property "Reference" "C53"
			(at 163.83 250.1836 90)
			(effects
				(font
					(size 1.27 1.27)
					(thickness 0.15)
				)
				(justify right)
			)
		)
		(property "Value" "C_100n_0402"
			(at 171.45 233.68 0)
			(effects
				(font
					(size 1.27 1.27)
					(thickness 0.15)
				)
				(justify left bottom)
				(hide yes)
			)
		)
		(property "Footprint" "antmicro-footprints:C_0402_1005Metric"
			(at 173.99 233.68 0)
			(effects
				(font
					(size 1.27 1.27)
					(thickness 0.15)
				)
				(justify left bottom)
				(hide yes)
			)
		)
		(property "Datasheet" "https://www.murata.com/products/productdetail?partno=GRM155R61H104KE14%23"
			(at 176.53 233.68 0)
			(effects
				(font
					(size 1.27 1.27)
					(thickness 0.15)
				)
				(justify left bottom)
				(hide yes)
			)
		)
		(property "Description" ""
			(at 161.29 254 0)
			(effects
				(font
					(size 1.27 1.27)
				)
				(hide yes)
			)
		)
		(property "MPN" "GRM155R61H104KE14D"
			(at 179.07 233.68 0)
			(effects
				(font
					(size 1.27 1.27)
					(thickness 0.15)
				)
				(justify left bottom)
				(hide yes)
			)
		)
		(property "Manufacturer" "Murata"
			(at 181.61 233.68 0)
			(effects
				(font
					(size 1.27 1.27)
					(thickness 0.15)
				)
				(justify left bottom)
				(hide yes)
			)
		)
		(property "License" "Apache-2.0"
			(at 184.15 233.68 0)
			(effects
				(font
					(size 1.27 1.27)
					(thickness 0.15)
				)
				(justify left bottom)
				(hide yes)
			)
		)
		(property "Author" "Antmicro"
			(at 186.69 233.68 0)
			(effects
				(font
					(size 1.27 1.27)
					(thickness 0.15)
				)
				(justify left bottom)
				(hide yes)
			)
		)
		(property "Val" "100n"
			(at 163.83 252.7236 90)
			(effects
				(font
					(size 1.27 1.27)
					(thickness 0.15)
				)
				(justify right)
			)
		)
		(property "Voltage" "50V"
			(at 189.23 233.68 0)
			(effects
				(font
					(size 1.27 1.27)
				)
				(justify left bottom)
				(hide yes)
			)
		)
		(property "Dielectric" "X5R"
			(at 191.77 233.68 0)
			(effects
				(font
					(size 1.27 1.27)
				)
				(justify left bottom)
				(hide yes)
			)
		)
		(property "Public" "False"
			(at 194.31 233.68 0)
			(effects
				(font
					(size 1.27 1.27)
				)
				(justify left bottom)
				(hide yes)
			)
		)
		(pin "1"
		)
		(pin "2"
		)
		(instances
			(project "com-express-7-baseboard"
				(path ""
					(reference "C53")
					(unit 1)
				)
			)
		)
	)
	(symbol
		(lib_id "antmicropower:+1V8")
		(at 351.79 133.35 0)
		(unit 1)
		(exclude_from_sim no)
		(in_bom yes)
		(on_board yes)
		(dnp no)
		(property "Reference" "#PWR0147"
			(at 367.03 135.89 0)
			(effects
				(font
					(size 1.27 1.27)
					(thickness 0.15)
				)
				(justify left bottom)
				(hide yes)
			)
		)
		(property "Value" "+1V8"
			(at 351.79 129.54 0)
			(effects
				(font
					(size 1.27 1.27)
					(thickness 0.15)
				)
			)
		)
		(property "Footprint" ""
			(at 367.03 140.97 0)
			(effects
				(font
					(size 1.27 1.27)
					(thickness 0.15)
				)
				(justify left bottom)
				(hide yes)
			)
		)
		(property "Datasheet" ""
			(at 367.03 143.51 0)
			(effects
				(font
					(size 1.27 1.27)
					(thickness 0.15)
				)
				(justify left bottom)
				(hide yes)
			)
		)
		(property "Description" ""
			(at 351.79 133.35 0)
			(effects
				(font
					(size 1.27 1.27)
				)
				(hide yes)
			)
		)
		(property "Author" "Antmicro"
			(at 367.03 138.43 0)
			(effects
				(font
					(size 1.27 1.27)
					(thickness 0.15)
				)
				(justify left bottom)
				(hide yes)
			)
		)
		(property "License" "Apache-2.0"
			(at 367.03 140.97 0)
			(effects
				(font
					(size 1.27 1.27)
					(thickness 0.15)
				)
				(justify left bottom)
				(hide yes)
			)
		)
		(pin "1"
		)
		(instances
			(project "com-express-7-baseboard"
				(path ""
					(reference "#PWR0147")
					(unit 1)
				)
			)
		)
	)
	(symbol
		(lib_id "antmicropower:GND")
		(at 88.9 252.73 0)
		(unit 1)
		(exclude_from_sim no)
		(in_bom yes)
		(on_board yes)
		(dnp no)
		(property "Reference" "#PWR0102"
			(at 97.79 255.27 0)
			(effects
				(font
					(size 1.27 1.27)
					(thickness 0.15)
				)
				(justify left bottom)
				(hide yes)
			)
		)
		(property "Value" "GND"
			(at 88.9 256.54 0)
			(effects
				(font
					(size 1.27 1.27)
					(thickness 0.15)
				)
			)
		)
		(property "Footprint" ""
			(at 97.79 260.35 0)
			(effects
				(font
					(size 1.27 1.27)
					(thickness 0.15)
				)
				(justify left bottom)
				(hide yes)
			)
		)
		(property "Datasheet" ""
			(at 97.79 265.43 0)
			(effects
				(font
					(size 1.27 1.27)
					(thickness 0.15)
				)
				(justify left bottom)
				(hide yes)
			)
		)
		(property "Description" ""
			(at 88.9 252.73 0)
			(effects
				(font
					(size 1.27 1.27)
				)
				(hide yes)
			)
		)
		(property "Author" "Antmicro"
			(at 97.79 260.35 0)
			(effects
				(font
					(size 1.27 1.27)
					(thickness 0.15)
				)
				(justify left bottom)
				(hide yes)
			)
		)
		(property "License" "Apache-2.0"
			(at 97.79 262.89 0)
			(effects
				(font
					(size 1.27 1.27)
					(thickness 0.15)
				)
				(justify left bottom)
				(hide yes)
			)
		)
		(pin "1"
		)
		(instances
			(project "com-express-7-baseboard"
				(path ""
					(reference "#PWR0102")
					(unit 1)
				)
			)
		)
	)
	(symbol
		(lib_id "antmicropower:GND")
		(at 161.29 254 0)
		(mirror y)
		(unit 1)
		(exclude_from_sim no)
		(in_bom yes)
		(on_board yes)
		(dnp no)
		(property "Reference" "#PWR0117"
			(at 152.4 256.54 0)
			(effects
				(font
					(size 1.27 1.27)
					(thickness 0.15)
				)
				(justify left bottom)
				(hide yes)
			)
		)
		(property "Value" "GND"
			(at 161.29 257.81 0)
			(effects
				(font
					(size 1.27 1.27)
					(thickness 0.15)
				)
			)
		)
		(property "Footprint" ""
			(at 152.4 261.62 0)
			(effects
				(font
					(size 1.27 1.27)
					(thickness 0.15)
				)
				(justify left bottom)
				(hide yes)
			)
		)
		(property "Datasheet" ""
			(at 152.4 266.7 0)
			(effects
				(font
					(size 1.27 1.27)
					(thickness 0.15)
				)
				(justify left bottom)
				(hide yes)
			)
		)
		(property "Description" ""
			(at 161.29 254 0)
			(effects
				(font
					(size 1.27 1.27)
				)
				(hide yes)
			)
		)
		(property "Author" "Antmicro"
			(at 152.4 261.62 0)
			(effects
				(font
					(size 1.27 1.27)
					(thickness 0.15)
				)
				(justify left bottom)
				(hide yes)
			)
		)
		(property "License" "Apache-2.0"
			(at 152.4 264.16 0)
			(effects
				(font
					(size 1.27 1.27)
					(thickness 0.15)
				)
				(justify left bottom)
				(hide yes)
			)
		)
		(pin "1"
		)
		(instances
			(project "com-express-7-baseboard"
				(path ""
					(reference "#PWR0117")
					(unit 1)
				)
			)
		)
	)
	(symbol
		(lib_id "antmicroLEDIndicationDiscrete:LED_G_0603_LTST-C190GKT")
		(at 245.11 214.63 270)
		(mirror x)
		(unit 1)
		(exclude_from_sim no)
		(in_bom yes)
		(on_board yes)
		(dnp no)
		(property "Reference" "D33"
			(at 245.745 210.185 90)
			(effects
				(font
					(size 1.27 1.27)
				)
				(justify left)
			)
		)
		(property "Value" "LED_G_0603_LTST-C190GKT"
			(at 237.49 191.77 0)
			(effects
				(font
					(size 1.27 1.27)
					(thickness 0.15)
				)
				(justify left bottom)
				(hide yes)
			)
		)
		(property "Footprint" "antmicro-footprints:LED_0603_1608Metric_G"
			(at 234.95 191.77 0)
			(effects
				(font
					(size 1.27 1.27)
					(thickness 0.15)
				)
				(justify left bottom)
				(hide yes)
			)
		)
		(property "Datasheet" "https://media.digikey.com/pdf/Data%20Sheets/Lite-On%20PDFs/LTST-C190GKT.pdf"
			(at 232.41 191.77 0)
			(effects
				(font
					(size 1.27 1.27)
					(thickness 0.15)
				)
				(justify left bottom)
				(hide yes)
			)
		)
		(property "Description" ""
			(at 245.11 214.63 0)
			(effects
				(font
					(size 1.27 1.27)
				)
				(hide yes)
			)
		)
		(property "MPN" "LTST-C190GKT"
			(at 248.92 209.5501 90)
			(effects
				(font
					(size 1.27 1.27)
					(thickness 0.15)
				)
				(justify left)
				(hide yes)
			)
		)
		(property "Manufacturer" "Lite-On"
			(at 227.33 191.77 0)
			(effects
				(font
					(size 1.27 1.27)
					(thickness 0.15)
				)
				(justify left bottom)
				(hide yes)
			)
		)
		(property "Author" "Antmicro"
			(at 224.79 191.77 0)
			(effects
				(font
					(size 1.27 1.27)
					(thickness 0.15)
				)
				(justify left bottom)
				(hide yes)
			)
		)
		(property "License" "Apache-2.0"
			(at 222.25 191.77 0)
			(effects
				(font
					(size 1.27 1.27)
					(thickness 0.15)
				)
				(justify left bottom)
				(hide yes)
			)
		)
		(property "Public" "False"
			(at 227.33 194.31 0)
			(effects
				(font
					(size 1.27 1.27)
				)
				(justify left bottom)
				(hide yes)
			)
		)
		(property "Color" "Green"
			(at 245.745 214.63 90)
			(effects
				(font
					(size 1.27 1.27)
				)
				(justify left)
			)
		)
		(pin "1"
		)
		(pin "2"
		)
		(instances
			(project "com-express-7-baseboard"
				(path ""
					(reference "D33")
					(unit 1)
				)
			)
		)
	)
	(symbol
		(lib_id "antmicropower:+3V3_AON")
		(at 194.31 153.67 0)
		(unit 1)
		(exclude_from_sim no)
		(in_bom yes)
		(on_board yes)
		(dnp no)
		(property "Reference" "#PWR0443"
			(at 194.31 157.48 0)
			(effects
				(font
					(size 1.27 1.27)
				)
				(hide yes)
			)
		)
		(property "Value" "+3V3_AON"
			(at 194.31 149.86 0)
			(effects
				(font
					(size 1.27 1.27)
				)
			)
		)
		(property "Footprint" ""
			(at 194.31 153.67 0)
			(effects
				(font
					(size 1.27 1.27)
				)
				(hide yes)
			)
		)
		(property "Datasheet" ""
			(at 194.31 153.67 0)
			(effects
				(font
					(size 1.27 1.27)
				)
				(hide yes)
			)
		)
		(property "Description" ""
			(at 194.31 153.67 0)
			(effects
				(font
					(size 1.27 1.27)
				)
				(hide yes)
			)
		)
		(pin "1"
		)
		(instances
			(project "com-express-7-baseboard"
				(path ""
					(reference "#PWR0443")
					(unit 1)
				)
			)
		)
	)
	(symbol
		(lib_id "antmicroTestPoints:TP_0.75mm_SMD")
		(at 257.81 248.92 0)
		(mirror x)
		(unit 1)
		(exclude_from_sim no)
		(in_bom no)
		(on_board yes)
		(dnp no)
		(property "Reference" "TP98"
			(at 261.62 248.92 0)
			(effects
				(font
					(size 1.27 1.27)
					(thickness 0.15)
				)
				(justify left)
			)
		)
		(property "Value" "TP_0.75mm_SMD"
			(at 268.605 245.11 0)
			(effects
				(font
					(size 1.27 1.27)
					(thickness 0.15)
				)
				(justify left bottom)
				(hide yes)
			)
		)
		(property "Footprint" "antmicro-footprints:TP_SMD_0.75mm"
			(at 268.605 242.57 0)
			(effects
				(font
					(size 1.27 1.27)
					(thickness 0.15)
				)
				(justify left bottom)
				(hide yes)
			)
		)
		(property "Datasheet" ""
			(at 275.59 236.22 0)
			(effects
				(font
					(size 1.27 1.27)
					(thickness 0.15)
				)
				(justify left bottom)
				(hide yes)
			)
		)
		(property "Description" ""
			(at 257.81 248.92 0)
			(effects
				(font
					(size 1.27 1.27)
				)
				(hide yes)
			)
		)
		(property "MPN" ""
			(at 268.605 237.49 0)
			(effects
				(font
					(size 1.27 1.27)
					(thickness 0.15)
				)
				(justify left bottom)
				(hide yes)
			)
		)
		(property "Manufacturer" ""
			(at 268.605 242.57 0)
			(effects
				(font
					(size 1.27 1.27)
					(thickness 0.15)
				)
				(justify left bottom)
				(hide yes)
			)
		)
		(property "Author" "Antmicro"
			(at 268.605 240.03 0)
			(effects
				(font
					(size 1.27 1.27)
					(thickness 0.15)
				)
				(justify left bottom)
				(hide yes)
			)
		)
		(property "License" "Apache-2.0"
			(at 268.605 237.49 0)
			(effects
				(font
					(size 1.27 1.27)
					(thickness 0.15)
				)
				(justify left bottom)
				(hide yes)
			)
		)
		(property "Public" "False"
			(at 267.97 234.95 0)
			(effects
				(font
					(size 1.27 1.27)
				)
				(justify left bottom)
				(hide yes)
			)
		)
		(pin "1"
		)
		(instances
			(project "com-express-7-baseboard"
				(path ""
					(reference "TP98")
					(unit 1)
				)
			)
		)
	)
	(symbol
		(lib_id "antmicroResistors0402:R_15k_0402")
		(at 248.92 59.69 90)
		(unit 1)
		(exclude_from_sim no)
		(in_bom yes)
		(on_board yes)
		(dnp no)
		(fields_autoplaced yes)
		(property "Reference" "R107"
			(at 251.46 55.8799 90)
			(effects
				(font
					(size 1.27 1.27)
					(thickness 0.15)
				)
				(justify right)
			)
		)
		(property "Value" "R_15k_0402"
			(at 261.62 39.37 0)
			(effects
				(font
					(size 1.27 1.27)
					(thickness 0.15)
				)
				(justify left bottom)
				(hide yes)
			)
		)
		(property "Footprint" "antmicro-footprints:R_0402_1005Metric"
			(at 264.16 39.37 0)
			(effects
				(font
					(size 1.27 1.27)
					(thickness 0.15)
				)
				(justify left bottom)
				(hide yes)
			)
		)
		(property "Datasheet" "https://www.bourns.com/docs/product-datasheets/cr.pdf"
			(at 266.7 39.37 0)
			(effects
				(font
					(size 1.27 1.27)
					(thickness 0.15)
				)
				(justify left bottom)
				(hide yes)
			)
		)
		(property "Description" ""
			(at 248.92 59.69 0)
			(effects
				(font
					(size 1.27 1.27)
				)
				(hide yes)
			)
		)
		(property "MPN" "CR0402-FX-1502GLF"
			(at 269.24 39.37 0)
			(effects
				(font
					(size 1.27 1.27)
					(thickness 0.15)
				)
				(justify left bottom)
				(hide yes)
			)
		)
		(property "Manufacturer" "Bourns"
			(at 271.78 39.37 0)
			(effects
				(font
					(size 1.27 1.27)
					(thickness 0.15)
				)
				(justify left bottom)
				(hide yes)
			)
		)
		(property "License" "Apache-2.0"
			(at 274.32 39.37 0)
			(effects
				(font
					(size 1.27 1.27)
					(thickness 0.15)
				)
				(justify left bottom)
				(hide yes)
			)
		)
		(property "Author" "Antmicro"
			(at 276.86 39.37 0)
			(effects
				(font
					(size 1.27 1.27)
					(thickness 0.15)
				)
				(justify left bottom)
				(hide yes)
			)
		)
		(property "Val" "15k"
			(at 251.46 58.4199 90)
			(effects
				(font
					(size 1.27 1.27)
					(thickness 0.15)
				)
				(justify right)
			)
		)
		(property "Tolerance" "1%"
			(at 259.08 39.37 0)
			(effects
				(font
					(size 1.27 1.27)
				)
				(justify left bottom)
				(hide yes)
			)
		)
		(property "Public" "False"
			(at 279.4 39.37 0)
			(effects
				(font
					(size 1.27 1.27)
				)
				(justify left bottom)
				(hide yes)
			)
		)
		(pin "2"
		)
		(pin "1"
		)
		(instances
			(project "com-express-7-baseboard"
				(path ""
					(reference "R107")
					(unit 1)
				)
			)
		)
	)
	(symbol
		(lib_id "antmicroCapacitors0402:C_100n_0402")
		(at 124.46 124.46 0)
		(unit 1)
		(exclude_from_sim no)
		(in_bom yes)
		(on_board yes)
		(dnp no)
		(fields_autoplaced yes)
		(property "Reference" "C48"
			(at 127.0063 118.11 0)
			(effects
				(font
					(size 1.27 1.27)
					(thickness 0.15)
				)
			)
		)
		(property "Value" "C_100n_0402"
			(at 144.78 134.62 0)
			(effects
				(font
					(size 1.27 1.27)
					(thickness 0.15)
				)
				(justify left bottom)
				(hide yes)
			)
		)
		(property "Footprint" "antmicro-footprints:C_0402_1005Metric"
			(at 144.78 137.16 0)
			(effects
				(font
					(size 1.27 1.27)
					(thickness 0.15)
				)
				(justify left bottom)
				(hide yes)
			)
		)
		(property "Datasheet" "https://www.murata.com/products/productdetail?partno=GRM155R61H104KE14%23"
			(at 144.78 139.7 0)
			(effects
				(font
					(size 1.27 1.27)
					(thickness 0.15)
				)
				(justify left bottom)
				(hide yes)
			)
		)
		(property "Description" ""
			(at 124.46 124.46 0)
			(effects
				(font
					(size 1.27 1.27)
				)
				(hide yes)
			)
		)
		(property "MPN" "GRM155R61H104KE14D"
			(at 144.78 142.24 0)
			(effects
				(font
					(size 1.27 1.27)
					(thickness 0.15)
				)
				(justify left bottom)
				(hide yes)
			)
		)
		(property "Manufacturer" "Murata"
			(at 144.78 144.78 0)
			(effects
				(font
					(size 1.27 1.27)
					(thickness 0.15)
				)
				(justify left bottom)
				(hide yes)
			)
		)
		(property "License" "Apache-2.0"
			(at 144.78 147.32 0)
			(effects
				(font
					(size 1.27 1.27)
					(thickness 0.15)
				)
				(justify left bottom)
				(hide yes)
			)
		)
		(property "Author" "Antmicro"
			(at 144.78 149.86 0)
			(effects
				(font
					(size 1.27 1.27)
					(thickness 0.15)
				)
				(justify left bottom)
				(hide yes)
			)
		)
		(property "Val" "100n"
			(at 127.0063 120.65 0)
			(effects
				(font
					(size 1.27 1.27)
					(thickness 0.15)
				)
			)
		)
		(property "Voltage" "50V"
			(at 144.78 152.4 0)
			(effects
				(font
					(size 1.27 1.27)
				)
				(justify left bottom)
				(hide yes)
			)
		)
		(property "Dielectric" "X5R"
			(at 144.78 154.94 0)
			(effects
				(font
					(size 1.27 1.27)
				)
				(justify left bottom)
				(hide yes)
			)
		)
		(property "Public" "False"
			(at 144.78 157.48 0)
			(effects
				(font
					(size 1.27 1.27)
				)
				(justify left bottom)
				(hide yes)
			)
		)
		(pin "2"
		)
		(pin "1"
		)
		(instances
			(project "com-express-7-baseboard"
				(path ""
					(reference "C48")
					(unit 1)
				)
			)
		)
	)
	(symbol
		(lib_id "antmicroResistors0402:R_10k_0402")
		(at 90.17 74.93 90)
		(unit 1)
		(exclude_from_sim no)
		(in_bom yes)
		(on_board yes)
		(dnp no)
		(fields_autoplaced yes)
		(property "Reference" "R89"
			(at 92.71 71.1199 90)
			(effects
				(font
					(size 1.27 1.27)
					(thickness 0.15)
				)
				(justify right)
			)
		)
		(property "Value" "R_10k_0402"
			(at 102.87 54.61 0)
			(effects
				(font
					(size 1.27 1.27)
					(thickness 0.15)
				)
				(justify left bottom)
				(hide yes)
			)
		)
		(property "Footprint" "antmicro-footprints:R_0402_1005Metric"
			(at 105.41 54.61 0)
			(effects
				(font
					(size 1.27 1.27)
					(thickness 0.15)
				)
				(justify left bottom)
				(hide yes)
			)
		)
		(property "Datasheet" "https://www.bourns.com/docs/product-datasheets/cr.pdf"
			(at 107.95 54.61 0)
			(effects
				(font
					(size 1.27 1.27)
					(thickness 0.15)
				)
				(justify left bottom)
				(hide yes)
			)
		)
		(property "Description" ""
			(at 90.17 74.93 0)
			(effects
				(font
					(size 1.27 1.27)
				)
				(hide yes)
			)
		)
		(property "MPN" "CR0402-FX-1002GLF"
			(at 110.49 54.61 0)
			(effects
				(font
					(size 1.27 1.27)
					(thickness 0.15)
				)
				(justify left bottom)
				(hide yes)
			)
		)
		(property "Manufacturer" "Bourns"
			(at 113.03 54.61 0)
			(effects
				(font
					(size 1.27 1.27)
					(thickness 0.15)
				)
				(justify left bottom)
				(hide yes)
			)
		)
		(property "License" "Apache-2.0"
			(at 115.57 54.61 0)
			(effects
				(font
					(size 1.27 1.27)
					(thickness 0.15)
				)
				(justify left bottom)
				(hide yes)
			)
		)
		(property "Author" "Antmicro"
			(at 118.11 54.61 0)
			(effects
				(font
					(size 1.27 1.27)
					(thickness 0.15)
				)
				(justify left bottom)
				(hide yes)
			)
		)
		(property "Val" "10k"
			(at 92.71 73.6599 90)
			(effects
				(font
					(size 1.27 1.27)
					(thickness 0.15)
				)
				(justify right)
			)
		)
		(property "Tolerance" "1%"
			(at 100.33 54.61 0)
			(effects
				(font
					(size 1.27 1.27)
				)
				(justify left bottom)
				(hide yes)
			)
		)
		(property "Public" "False"
			(at 120.65 54.61 0)
			(effects
				(font
					(size 1.27 1.27)
				)
				(justify left bottom)
				(hide yes)
			)
		)
		(pin "1"
		)
		(pin "2"
		)
		(instances
			(project "com-express-7-baseboard"
				(path ""
					(reference "R89")
					(unit 1)
				)
			)
		)
	)
	(symbol
		(lib_id "antmicropower:+5V_AON")
		(at 334.01 218.44 0)
		(unit 1)
		(exclude_from_sim no)
		(in_bom yes)
		(on_board yes)
		(dnp no)
		(property "Reference" "#PWR0142"
			(at 334.01 222.25 0)
			(effects
				(font
					(size 1.27 1.27)
				)
				(hide yes)
			)
		)
		(property "Value" "+5V_AON"
			(at 334.01 214.63 0)
			(effects
				(font
					(size 1.27 1.27)
				)
			)
		)
		(property "Footprint" ""
			(at 334.01 218.44 0)
			(effects
				(font
					(size 1.27 1.27)
				)
				(hide yes)
			)
		)
		(property "Datasheet" ""
			(at 334.01 218.44 0)
			(effects
				(font
					(size 1.27 1.27)
				)
				(hide yes)
			)
		)
		(property "Description" ""
			(at 334.01 218.44 0)
			(effects
				(font
					(size 1.27 1.27)
				)
				(hide yes)
			)
		)
		(pin "1"
		)
		(instances
			(project "com-express-7-baseboard"
				(path ""
					(reference "#PWR0142")
					(unit 1)
				)
			)
		)
	)
	(symbol
		(lib_id "antmicropower:+3V3")
		(at 236.22 243.84 0)
		(unit 1)
		(exclude_from_sim no)
		(in_bom yes)
		(on_board yes)
		(dnp no)
		(property "Reference" "#PWR017"
			(at 251.46 243.84 0)
			(effects
				(font
					(size 1.27 1.27)
					(thickness 0.15)
				)
				(justify left bottom)
				(hide yes)
			)
		)
		(property "Value" "+3V3"
			(at 236.22 240.03 0)
			(effects
				(font
					(size 1.27 1.27)
					(thickness 0.15)
				)
			)
		)
		(property "Footprint" ""
			(at 251.46 251.46 0)
			(effects
				(font
					(size 1.27 1.27)
					(thickness 0.15)
				)
				(justify left bottom)
				(hide yes)
			)
		)
		(property "Datasheet" ""
			(at 251.46 254 0)
			(effects
				(font
					(size 1.27 1.27)
					(thickness 0.15)
				)
				(justify left bottom)
				(hide yes)
			)
		)
		(property "Description" ""
			(at 236.22 243.84 0)
			(effects
				(font
					(size 1.27 1.27)
				)
				(hide yes)
			)
		)
		(property "Author" "Antmicro"
			(at 251.46 246.38 0)
			(effects
				(font
					(size 1.27 1.27)
					(thickness 0.15)
				)
				(justify left bottom)
				(hide yes)
			)
		)
		(property "License" "Apache-2.0"
			(at 251.46 248.92 0)
			(effects
				(font
					(size 1.27 1.27)
					(thickness 0.15)
				)
				(justify left bottom)
				(hide yes)
			)
		)
		(pin "1"
		)
		(instances
			(project "com-express-7-baseboard"
				(path ""
					(reference "#PWR017")
					(unit 1)
				)
			)
		)
	)
	(symbol
		(lib_id "antmicroTVSDiodes:SMF4L15A")
		(at 48.26 226.06 90)
		(mirror x)
		(unit 1)
		(exclude_from_sim no)
		(in_bom yes)
		(on_board yes)
		(dnp no)
		(fields_autoplaced yes)
		(property "Reference" "D24"
			(at 45.72 227.3299 90)
			(effects
				(font
					(size 1.27 1.27)
					(thickness 0.15)
				)
				(justify left)
			)
		)
		(property "Value" "SMF4L15A"
			(at 63.5 252.73 0)
			(effects
				(font
					(size 1.27 1.27)
					(thickness 0.15)
				)
				(justify left bottom)
				(hide yes)
			)
		)
		(property "Footprint" "antmicro-footprints:SOD-123FL"
			(at 58.42 252.73 0)
			(effects
				(font
					(size 1.27 1.27)
					(thickness 0.15)
				)
				(justify left bottom)
				(hide yes)
			)
		)
		(property "Datasheet" "https://www.littelfuse.com/media?resourcetype=datasheets&itemid=d2ba8fab-1de3-4176-8530-f36ecb0b8799&filename=smf4l"
			(at 60.96 252.73 0)
			(effects
				(font
					(size 1.27 1.27)
					(thickness 0.15)
				)
				(justify left bottom)
				(hide yes)
			)
		)
		(property "Description" ""
			(at 48.26 226.06 0)
			(effects
				(font
					(size 1.27 1.27)
				)
				(hide yes)
			)
		)
		(property "MPN" "SMF4L15A"
			(at 45.72 229.8699 90)
			(effects
				(font
					(size 1.27 1.27)
					(thickness 0.15)
				)
				(justify left)
			)
		)
		(property "Manufacturer" "Littelfuse"
			(at 66.04 252.73 0)
			(effects
				(font
					(size 1.27 1.27)
					(thickness 0.15)
				)
				(justify left bottom)
				(hide yes)
			)
		)
		(property "Author" "Antmicro"
			(at 68.58 252.73 0)
			(effects
				(font
					(size 1.27 1.27)
					(thickness 0.15)
				)
				(justify left bottom)
				(hide yes)
			)
		)
		(property "License" "Apache-2.0"
			(at 71.12 252.73 0)
			(effects
				(font
					(size 1.27 1.27)
					(thickness 0.15)
				)
				(justify left bottom)
				(hide yes)
			)
		)
		(property "Public" "False"
			(at 66.04 246.38 0)
			(effects
				(font
					(size 1.27 1.27)
				)
				(justify left bottom)
				(hide yes)
			)
		)
		(pin "1"
		)
		(pin "2"
		)
		(instances
			(project "com-express-7-baseboard"
				(path ""
					(reference "D24")
					(unit 1)
				)
			)
		)
	)
	(symbol
		(lib_id "antmicropower:PWR_FLAG")
		(at 351.79 134.62 270)
		(unit 1)
		(exclude_from_sim no)
		(in_bom yes)
		(on_board yes)
		(dnp no)
		(fields_autoplaced yes)
		(property "Reference" "#FLG011"
			(at 353.695 134.62 0)
			(effects
				(font
					(size 1.27 1.27)
				)
				(hide yes)
			)
		)
		(property "Value" "PWR_FLAG"
			(at 355.6 134.6199 90)
			(effects
				(font
					(size 1.27 1.27)
				)
				(justify left)
			)
		)
		(property "Footprint" ""
			(at 351.79 134.62 0)
			(effects
				(font
					(size 1.27 1.27)
				)
				(hide yes)
			)
		)
		(property "Datasheet" ""
			(at 351.79 134.62 0)
			(effects
				(font
					(size 1.27 1.27)
				)
				(hide yes)
			)
		)
		(property "Description" ""
			(at 351.79 134.62 0)
			(effects
				(font
					(size 1.27 1.27)
				)
				(hide yes)
			)
		)
		(pin "1"
		)
		(instances
			(project "com-express-7-baseboard"
				(path ""
					(reference "#FLG011")
					(unit 1)
				)
			)
		)
	)
	(symbol
		(lib_id "antmicroCapacitors0603:C_22u_16V_0603")
		(at 58.42 132.08 90)
		(unit 1)
		(exclude_from_sim no)
		(in_bom yes)
		(on_board yes)
		(dnp no)
		(fields_autoplaced yes)
		(property "Reference" "C40"
			(at 60.96 126.9935 90)
			(effects
				(font
					(size 1.27 1.27)
					(thickness 0.15)
				)
				(justify right)
			)
		)
		(property "Value" "C_22u_16V_0603"
			(at 68.58 111.76 0)
			(effects
				(font
					(size 1.27 1.27)
					(thickness 0.15)
				)
				(justify left bottom)
				(hide yes)
			)
		)
		(property "Footprint" "antmicro-footprints:C_0603_1608Metric"
			(at 71.12 111.76 0)
			(effects
				(font
					(size 1.27 1.27)
					(thickness 0.15)
				)
				(justify left bottom)
				(hide yes)
			)
		)
		(property "Datasheet" "https://product.samsungsem.com/mlcc/CL10A226MO7JZN.do"
			(at 73.66 111.76 0)
			(effects
				(font
					(size 1.27 1.27)
					(thickness 0.15)
				)
				(justify left bottom)
				(hide yes)
			)
		)
		(property "Description" ""
			(at 58.42 132.08 0)
			(effects
				(font
					(size 1.27 1.27)
				)
				(hide yes)
			)
		)
		(property "MPN" "CL10A226MO7JZNC"
			(at 76.2 111.76 0)
			(effects
				(font
					(size 1.27 1.27)
					(thickness 0.15)
				)
				(justify left bottom)
				(hide yes)
			)
		)
		(property "Manufacturer" "Samsung Electro-Mechanics"
			(at 78.74 111.76 0)
			(effects
				(font
					(size 1.27 1.27)
					(thickness 0.15)
				)
				(justify left bottom)
				(hide yes)
			)
		)
		(property "License" "Apache-2.0"
			(at 81.28 111.76 0)
			(effects
				(font
					(size 1.27 1.27)
					(thickness 0.15)
				)
				(justify left bottom)
				(hide yes)
			)
		)
		(property "Author" "Antmicro"
			(at 83.82 111.76 0)
			(effects
				(font
					(size 1.27 1.27)
					(thickness 0.15)
				)
				(justify left bottom)
				(hide yes)
			)
		)
		(property "Val" "22u"
			(at 60.96 129.5335 90)
			(effects
				(font
					(size 1.27 1.27)
					(thickness 0.15)
				)
				(justify right)
			)
		)
		(property "Voltage" "16V"
			(at 60.96 132.0735 90)
			(effects
				(font
					(size 1.27 1.27)
				)
				(justify right)
				(hide yes)
			)
		)
		(property "Dielectric" ""
			(at 88.9 111.76 0)
			(effects
				(font
					(size 1.27 1.27)
				)
				(justify left bottom)
				(hide yes)
			)
		)
		(property "Public" "False"
			(at 91.44 111.76 0)
			(effects
				(font
					(size 1.27 1.27)
				)
				(justify left bottom)
				(hide yes)
			)
		)
		(pin "2"
		)
		(pin "1"
		)
		(instances
			(project "com-express-7-baseboard"
				(path ""
					(reference "C40")
					(unit 1)
				)
			)
		)
	)
	(symbol
		(lib_id "antmicroCapacitors0402:C_100n_0402")
		(at 170.18 254 90)
		(unit 1)
		(exclude_from_sim no)
		(in_bom yes)
		(on_board yes)
		(dnp no)
		(fields_autoplaced yes)
		(property "Reference" "C55"
			(at 172.72 250.1836 90)
			(effects
				(font
					(size 1.27 1.27)
					(thickness 0.15)
				)
				(justify right)
			)
		)
		(property "Value" "C_100n_0402"
			(at 180.34 233.68 0)
			(effects
				(font
					(size 1.27 1.27)
					(thickness 0.15)
				)
				(justify left bottom)
				(hide yes)
			)
		)
		(property "Footprint" "antmicro-footprints:C_0402_1005Metric"
			(at 182.88 233.68 0)
			(effects
				(font
					(size 1.27 1.27)
					(thickness 0.15)
				)
				(justify left bottom)
				(hide yes)
			)
		)
		(property "Datasheet" "https://www.murata.com/products/productdetail?partno=GRM155R61H104KE14%23"
			(at 185.42 233.68 0)
			(effects
				(font
					(size 1.27 1.27)
					(thickness 0.15)
				)
				(justify left bottom)
				(hide yes)
			)
		)
		(property "Description" ""
			(at 170.18 254 0)
			(effects
				(font
					(size 1.27 1.27)
				)
				(hide yes)
			)
		)
		(property "MPN" "GRM155R61H104KE14D"
			(at 187.96 233.68 0)
			(effects
				(font
					(size 1.27 1.27)
					(thickness 0.15)
				)
				(justify left bottom)
				(hide yes)
			)
		)
		(property "Manufacturer" "Murata"
			(at 190.5 233.68 0)
			(effects
				(font
					(size 1.27 1.27)
					(thickness 0.15)
				)
				(justify left bottom)
				(hide yes)
			)
		)
		(property "License" "Apache-2.0"
			(at 193.04 233.68 0)
			(effects
				(font
					(size 1.27 1.27)
					(thickness 0.15)
				)
				(justify left bottom)
				(hide yes)
			)
		)
		(property "Author" "Antmicro"
			(at 195.58 233.68 0)
			(effects
				(font
					(size 1.27 1.27)
					(thickness 0.15)
				)
				(justify left bottom)
				(hide yes)
			)
		)
		(property "Val" "100n"
			(at 172.72 252.7236 90)
			(effects
				(font
					(size 1.27 1.27)
					(thickness 0.15)
				)
				(justify right)
			)
		)
		(property "Voltage" "50V"
			(at 198.12 233.68 0)
			(effects
				(font
					(size 1.27 1.27)
				)
				(justify left bottom)
				(hide yes)
			)
		)
		(property "Dielectric" "X5R"
			(at 200.66 233.68 0)
			(effects
				(font
					(size 1.27 1.27)
				)
				(justify left bottom)
				(hide yes)
			)
		)
		(property "Public" "False"
			(at 203.2 233.68 0)
			(effects
				(font
					(size 1.27 1.27)
				)
				(justify left bottom)
				(hide yes)
			)
		)
		(pin "1"
		)
		(pin "2"
		)
		(instances
			(project "com-express-7-baseboard"
				(path ""
					(reference "C55")
					(unit 1)
				)
			)
		)
	)
)
